FILE_TYPE = MACRO_DRAWING;
SET COLOR_WIRE YELLOW;
SET COLOR_PROP ORANGE;
SET COLOR_DOT WHITE;
SET COLOR_ARC YELLOW;
SET COLOR_BODY GREEN;
SET COLOR_NOTE PURPLE;
SET PROP_DISPLAY VALUE;
SET PAGE_NUMBER P136;
FORCEADD UNIVERSAL_GND..1
(-4325 -2875);
FORCEPROP 3 LASTPIN (-4325 -2825) SIG_NAME GND\g
J 0
(-4315 -2815);
DISPLAY 0.659574 (-4315 -2815);
PAINT MONO (-4315 -2815);
DISPLAY INVISIBLE (-4315 -2815);
FORCEPROP 2 LAST ROOM IO_SLOT
J 1
(-4550 -2800);
DISPLAY 0.744681 (-4550 -2800);
DISPLAY INVISIBLE (-4550 -2800);
FORCEPROP 2 LAST CDS_LIB logical_power
J 0
(-4325 -2875);
DISPLAY INVISIBLE (-4325 -2875);
FORCEPROP 1 LAST HDL_POWER GND
J 1
(-4300 -2950);
DISPLAY 0.872340 (-4300 -2950);
PAINT GREEN (-4300 -2950);
DISPLAY INVISIBLE (-4300 -2950);
FORCEPROP 1 LAST PATH I1
J 0
(-4250 -2875);
DISPLAY 0.872340 (-4250 -2875);
PAINT AQUA (-4250 -2875);
DISPLAY INVISIBLE (-4250 -2875);
FORCEADD UNIVERSAL_POWER..1
(-3950 -1700);
FORCEPROP 3 LASTPIN (-3950 -1750) SIG_NAME P3V3_AUX\g
J 0
(-3940 -1740);
DISPLAY 0.659574 (-3940 -1740);
PAINT MONO (-3940 -1740);
DISPLAY INVISIBLE (-3940 -1740);
FORCEPROP 1 LAST HDL_POWER P3V3_AUX
J 1
(-3950 -1650);
DISPLAY 0.872340 (-3950 -1650);
PAINT GREEN (-3950 -1650);
FORCEPROP 2 LAST CDS_LIB logical_power
J 0
(-3950 -1700);
DISPLAY INVISIBLE (-3950 -1700);
FORCEPROP 1 LAST PATH I10
J 0
(-3900 -1675);
DISPLAY 0.872340 (-3900 -1675);
PAINT AQUA (-3900 -1675);
DISPLAY INVISIBLE (-3900 -1675);
FORCEADD UNIVERSAL_GND..1
(-4500 -1150);
FORCEPROP 3 LASTPIN (-4500 -1100) SIG_NAME GND\g
J 0
(-4490 -1090);
DISPLAY 0.659574 (-4490 -1090);
PAINT MONO (-4490 -1090);
DISPLAY INVISIBLE (-4490 -1090);
FORCEPROP 2 LAST ROOM IO_SLOT
J 1
(-4725 -1075);
DISPLAY 0.744681 (-4725 -1075);
DISPLAY INVISIBLE (-4725 -1075);
FORCEPROP 2 LAST CDS_LIB logical_power
J 0
(-4500 -1150);
DISPLAY INVISIBLE (-4500 -1150);
FORCEPROP 1 LAST HDL_POWER GND
J 1
(-4475 -1225);
DISPLAY 0.872340 (-4475 -1225);
PAINT GREEN (-4475 -1225);
DISPLAY INVISIBLE (-4475 -1225);
FORCEPROP 1 LAST PATH I11
J 0
(-4425 -1150);
DISPLAY 0.872340 (-4425 -1150);
PAINT AQUA (-4425 -1150);
DISPLAY INVISIBLE (-4425 -1150);
FORCEADD Q_RES..2
(-4500 -800);
FORCEPROP 1 LAST PART_NUMBER CS36802FB04
J 0
(-4460 -925);
DISPLAY 0.638298 (-4460 -925);
DISPLAY INVISIBLE (-4460 -925);
FORCEPROP 1 LAST MATERIAL EMPTY
J 0
(-4460 -875);
DISPLAY 0.638298 (-4460 -875);
PAINT RED (-4460 -875);
FORCEPROP 1 LAST PACK_TYPE 0402LF
J 0
(-4460 -975);
DISPLAY 0.638298 (-4460 -975);
FORCEPROP 1 LAST VALUE 68K
J 0
(-4455 -725);
DISPLAY 0.638298 (-4455 -725);
FORCEPROP 1 LAST TOLERANCE 1%
J 0
(-4455 -775);
DISPLAY 0.638298 (-4455 -775);
FORCEPROP 1 LAST WATTAGE 1/16W
J 0
(-4460 -825);
DISPLAY 0.638298 (-4460 -825);
FORCEPROP 1 LAST $LOCATION R3267
J 0
(-4455 -675);
DISPLAY 0.638298 (-4455 -675);
FORCEPROP 1 LASTPIN (-4500 -700) $PN 1
J 0
(-4495 -738);
DISPLAY 0.787234 (-4495 -738);
PAINT MONO (-4495 -738);
FORCEPROP 1 LASTPIN (-4500 -900) $PN 2
J 0
(-4495 -890);
DISPLAY 0.787234 (-4495 -890);
PAINT MONO (-4495 -890);
FORCEPROP 2 LAST CDS_LIB pure_quanta
J 0
(-4500 -800);
DISPLAY INVISIBLE (-4500 -800);
FORCEPROP 1 LAST PATH I12
J 0
(-4450 -625);
DISPLAY 0.978723 (-4450 -625);
PAINT WHITE (-4450 -625);
DISPLAY INVISIBLE (-4450 -625);
FORCEPROP 0 LAST CDS_LOCATION R3267
J 0
(-4450 -625);
DISPLAY 1.021277 (-4450 -625);
DISPLAY INVISIBLE (-4450 -625);
FORCEPROP 0 LAST $SEC 1
J 0
(-4450 -625);
DISPLAY 0.680851 (-4450 -625);
PAINT MONO (-4450 -625);
DISPLAY INVISIBLE (-4450 -625);
FORCEPROP 0 LAST CDS_SEC 1
J 0
(-4450 -625);
DISPLAY 1.021277 (-4450 -625);
DISPLAY INVISIBLE (-4450 -625);
FORCEADD UNIVERSAL_GND..1
(-4125 -1150);
FORCEPROP 3 LASTPIN (-4125 -1100) SIG_NAME GND\g
J 0
(-4115 -1090);
DISPLAY 0.659574 (-4115 -1090);
PAINT MONO (-4115 -1090);
DISPLAY INVISIBLE (-4115 -1090);
FORCEPROP 2 LAST ROOM IO_SLOT
J 1
(-4350 -1075);
DISPLAY 0.744681 (-4350 -1075);
DISPLAY INVISIBLE (-4350 -1075);
FORCEPROP 2 LAST CDS_LIB logical_power
J 0
(-4125 -1150);
DISPLAY INVISIBLE (-4125 -1150);
FORCEPROP 1 LAST HDL_POWER GND
J 1
(-4100 -1225);
DISPLAY 0.872340 (-4100 -1225);
PAINT GREEN (-4100 -1225);
DISPLAY INVISIBLE (-4100 -1225);
FORCEPROP 1 LAST PATH I13
J 0
(-4050 -1150);
DISPLAY 0.872340 (-4050 -1150);
PAINT AQUA (-4050 -1150);
DISPLAY INVISIBLE (-4050 -1150);
FORCEADD Q_RES..2
(-4125 -800);
FORCEPROP 1 LAST PART_NUMBER CS21002FB06
J 0
(-4085 -925);
DISPLAY 0.638298 (-4085 -925);
DISPLAY INVISIBLE (-4085 -925);
FORCEPROP 1 LAST VALUE 1K
J 0
(-4080 -725);
DISPLAY 0.638298 (-4080 -725);
FORCEPROP 1 LAST TOLERANCE 1%
J 0
(-4080 -775);
DISPLAY 0.638298 (-4080 -775);
FORCEPROP 1 LAST PACK_TYPE 0402LF
J 0
(-4085 -975);
DISPLAY 0.638298 (-4085 -975);
FORCEPROP 1 LAST MATERIAL EMPTY
J 0
(-4085 -875);
DISPLAY 0.638298 (-4085 -875);
PAINT RED (-4085 -875);
FORCEPROP 1 LAST WATTAGE 1/16W
J 0
(-4085 -825);
DISPLAY 0.638298 (-4085 -825);
FORCEPROP 1 LAST $LOCATION R3270
J 0
(-4080 -675);
DISPLAY 0.978723 (-4080 -675);
FORCEPROP 1 LASTPIN (-4125 -700) $PN 1
J 0
(-4120 -738);
DISPLAY 0.787234 (-4120 -738);
PAINT MONO (-4120 -738);
FORCEPROP 1 LASTPIN (-4125 -900) $PN 2
J 0
(-4120 -890);
DISPLAY 0.787234 (-4120 -890);
PAINT MONO (-4120 -890);
FORCEPROP 2 LAST CDS_LIB pure_quanta
J 0
(-4125 -800);
DISPLAY INVISIBLE (-4125 -800);
FORCEPROP 1 LAST PATH I14
J 0
(-4075 -625);
DISPLAY 0.978723 (-4075 -625);
PAINT WHITE (-4075 -625);
DISPLAY INVISIBLE (-4075 -625);
FORCEPROP 0 LAST CDS_LOCATION R3270
J 0
(-4075 -625);
DISPLAY 1.021277 (-4075 -625);
DISPLAY INVISIBLE (-4075 -625);
FORCEPROP 0 LAST $SEC 1
J 0
(-4075 -625);
DISPLAY 0.680851 (-4075 -625);
PAINT MONO (-4075 -625);
DISPLAY INVISIBLE (-4075 -625);
FORCEPROP 0 LAST CDS_SEC 1
J 0
(-4075 -625);
DISPLAY 1.021277 (-4075 -625);
DISPLAY INVISIBLE (-4075 -625);
FORCEADD Q_RES..2
(-4125 -275);
FORCEPROP 1 LAST PART_NUMBER CS21002FB06
J 0
(-4085 -400);
DISPLAY 0.638298 (-4085 -400);
DISPLAY INVISIBLE (-4085 -400);
FORCEPROP 1 LAST PACK_TYPE 0402LF
J 0
(-4085 -450);
DISPLAY 0.638298 (-4085 -450);
FORCEPROP 1 LAST MATERIAL EMPTY
J 0
(-4085 -350);
DISPLAY 0.638298 (-4085 -350);
PAINT RED (-4085 -350);
FORCEPROP 1 LAST TOLERANCE 1%
J 0
(-4080 -250);
DISPLAY 0.638298 (-4080 -250);
FORCEPROP 1 LAST VALUE 1K
J 0
(-4080 -200);
DISPLAY 0.638298 (-4080 -200);
FORCEPROP 1 LAST WATTAGE 1/16W
J 0
(-4085 -300);
DISPLAY 0.638298 (-4085 -300);
FORCEPROP 1 LAST $LOCATION R3269
J 0
(-4080 -150);
DISPLAY 0.638298 (-4080 -150);
FORCEPROP 1 LASTPIN (-4125 -175) $PN 1
J 0
(-4120 -213);
DISPLAY 0.787234 (-4120 -213);
PAINT MONO (-4120 -213);
FORCEPROP 1 LASTPIN (-4125 -375) $PN 2
J 0
(-4120 -365);
DISPLAY 0.787234 (-4120 -365);
PAINT MONO (-4120 -365);
FORCEPROP 2 LAST CDS_LIB pure_quanta
J 0
(-4125 -275);
DISPLAY INVISIBLE (-4125 -275);
FORCEPROP 1 LAST PATH I15
J 0
(-4075 -100);
DISPLAY 0.978723 (-4075 -100);
PAINT WHITE (-4075 -100);
DISPLAY INVISIBLE (-4075 -100);
FORCEPROP 0 LAST CDS_LOCATION R3269
J 0
(-4075 -100);
DISPLAY 1.021277 (-4075 -100);
DISPLAY INVISIBLE (-4075 -100);
FORCEPROP 0 LAST $SEC 1
J 0
(-4075 -100);
DISPLAY 0.680851 (-4075 -100);
PAINT MONO (-4075 -100);
DISPLAY INVISIBLE (-4075 -100);
FORCEPROP 0 LAST CDS_SEC 1
J 0
(-4075 -100);
DISPLAY 1.021277 (-4075 -100);
DISPLAY INVISIBLE (-4075 -100);
FORCEADD Q_RES..2
(-3075 -2000);
FORCEPROP 1 LAST PART_NUMBER CS21002FB06
J 0
(-3035 -2125);
DISPLAY 0.638298 (-3035 -2125);
DISPLAY INVISIBLE (-3035 -2125);
FORCEPROP 1 LAST WATTAGE 1/16W
J 0
(-3035 -2025);
DISPLAY 0.638298 (-3035 -2025);
FORCEPROP 1 LAST VALUE 1K
J 0
(-3030 -1925);
DISPLAY 0.638298 (-3030 -1925);
FORCEPROP 1 LAST TOLERANCE 1%
J 0
(-3030 -1975);
DISPLAY 0.638298 (-3030 -1975);
FORCEPROP 1 LAST MATERIAL EMPTY
J 0
(-3035 -2075);
DISPLAY 0.638298 (-3035 -2075);
PAINT RED (-3035 -2075);
FORCEPROP 1 LAST PACK_TYPE 0402LF
J 0
(-3035 -2175);
DISPLAY 0.638298 (-3035 -2175);
FORCEPROP 1 LAST $LOCATION R3277
J 0
(-3030 -1875);
DISPLAY 0.978723 (-3030 -1875);
FORCEPROP 1 LASTPIN (-3075 -1900) $PN 1
J 0
(-3070 -1938);
DISPLAY 0.787234 (-3070 -1938);
PAINT MONO (-3070 -1938);
FORCEPROP 1 LASTPIN (-3075 -2100) $PN 2
J 0
(-3070 -2090);
DISPLAY 0.787234 (-3070 -2090);
PAINT MONO (-3070 -2090);
FORCEPROP 2 LAST CDS_LIB pure_quanta
J 0
(-3075 -2000);
DISPLAY INVISIBLE (-3075 -2000);
FORCEPROP 1 LAST PATH I16
J 0
(-3025 -1825);
DISPLAY 0.978723 (-3025 -1825);
PAINT WHITE (-3025 -1825);
DISPLAY INVISIBLE (-3025 -1825);
FORCEPROP 0 LAST CDS_LOCATION R3277
J 0
(-3025 -1825);
DISPLAY 1.021277 (-3025 -1825);
DISPLAY INVISIBLE (-3025 -1825);
FORCEPROP 0 LAST $SEC 1
J 0
(-3025 -1825);
DISPLAY 0.680851 (-3025 -1825);
PAINT MONO (-3025 -1825);
DISPLAY INVISIBLE (-3025 -1825);
FORCEPROP 0 LAST CDS_SEC 1
J 0
(-3025 -1825);
DISPLAY 1.021277 (-3025 -1825);
DISPLAY INVISIBLE (-3025 -1825);
FORCEADD UNIVERSAL_GND..1
(-3650 -1150);
FORCEPROP 3 LASTPIN (-3650 -1100) SIG_NAME GND\g
J 0
(-3640 -1090);
DISPLAY 0.659574 (-3640 -1090);
PAINT MONO (-3640 -1090);
DISPLAY INVISIBLE (-3640 -1090);
FORCEPROP 2 LAST ROOM IO_SLOT
J 1
(-3875 -1075);
DISPLAY 0.744681 (-3875 -1075);
DISPLAY INVISIBLE (-3875 -1075);
FORCEPROP 2 LAST CDS_LIB logical_power
J 0
(-3650 -1150);
DISPLAY INVISIBLE (-3650 -1150);
FORCEPROP 1 LAST HDL_POWER GND
J 1
(-3625 -1225);
DISPLAY 0.872340 (-3625 -1225);
PAINT GREEN (-3625 -1225);
DISPLAY INVISIBLE (-3625 -1225);
FORCEPROP 1 LAST PATH I17
J 0
(-3575 -1150);
DISPLAY 0.872340 (-3575 -1150);
PAINT AQUA (-3575 -1150);
DISPLAY INVISIBLE (-3575 -1150);
FORCEADD Q_RES..2
(-3650 -825);
FORCEPROP 1 LAST PART_NUMBER CS36802FB04
J 0
(-3610 -950);
DISPLAY 0.638298 (-3610 -950);
DISPLAY INVISIBLE (-3610 -950);
FORCEPROP 1 LAST TOLERANCE 1%
J 0
(-3605 -800);
DISPLAY 0.638298 (-3605 -800);
FORCEPROP 1 LAST WATTAGE 1/16W
J 0
(-3610 -850);
DISPLAY 0.638298 (-3610 -850);
FORCEPROP 1 LAST MATERIAL EMPTY
J 0
(-3610 -900);
DISPLAY 0.638298 (-3610 -900);
PAINT RED (-3610 -900);
FORCEPROP 1 LAST PACK_TYPE 0402LF
J 0
(-3610 -1000);
DISPLAY 0.638298 (-3610 -1000);
FORCEPROP 1 LAST VALUE 68K
J 0
(-3605 -750);
DISPLAY 0.638298 (-3605 -750);
FORCEPROP 1 LAST $LOCATION R3273
J 0
(-3605 -700);
DISPLAY 0.978723 (-3605 -700);
FORCEPROP 1 LASTPIN (-3650 -725) $PN 1
J 0
(-3645 -763);
DISPLAY 0.787234 (-3645 -763);
PAINT MONO (-3645 -763);
FORCEPROP 1 LASTPIN (-3650 -925) $PN 2
J 0
(-3645 -915);
DISPLAY 0.787234 (-3645 -915);
PAINT MONO (-3645 -915);
FORCEPROP 2 LAST CDS_LIB pure_quanta
J 0
(-3650 -825);
DISPLAY INVISIBLE (-3650 -825);
FORCEPROP 1 LAST PATH I18
J 0
(-3600 -650);
DISPLAY 0.978723 (-3600 -650);
PAINT WHITE (-3600 -650);
DISPLAY INVISIBLE (-3600 -650);
FORCEPROP 0 LAST CDS_LOCATION R3273
J 0
(-3600 -650);
DISPLAY 1.021277 (-3600 -650);
DISPLAY INVISIBLE (-3600 -650);
FORCEPROP 0 LAST $SEC 1
J 0
(-3600 -650);
DISPLAY 0.680851 (-3600 -650);
PAINT MONO (-3600 -650);
DISPLAY INVISIBLE (-3600 -650);
FORCEPROP 0 LAST CDS_SEC 1
J 0
(-3600 -650);
DISPLAY 1.021277 (-3600 -650);
DISPLAY INVISIBLE (-3600 -650);
FORCEADD UNIVERSAL_GND..1
(-3250 -1150);
FORCEPROP 3 LASTPIN (-3250 -1100) SIG_NAME GND\g
J 0
(-3240 -1090);
DISPLAY 0.659574 (-3240 -1090);
PAINT MONO (-3240 -1090);
DISPLAY INVISIBLE (-3240 -1090);
FORCEPROP 2 LAST ROOM IO_SLOT
J 1
(-3475 -1075);
DISPLAY 0.744681 (-3475 -1075);
DISPLAY INVISIBLE (-3475 -1075);
FORCEPROP 2 LAST CDS_LIB logical_power
J 0
(-3250 -1150);
DISPLAY INVISIBLE (-3250 -1150);
FORCEPROP 1 LAST HDL_POWER GND
J 1
(-3225 -1225);
DISPLAY 0.872340 (-3225 -1225);
PAINT GREEN (-3225 -1225);
DISPLAY INVISIBLE (-3225 -1225);
FORCEPROP 1 LAST PATH I19
J 0
(-3175 -1150);
DISPLAY 0.872340 (-3175 -1150);
PAINT AQUA (-3175 -1150);
DISPLAY INVISIBLE (-3175 -1150);
FORCEADD Q_RES..2
(-4325 -2525);
FORCEPROP 1 LAST PART_NUMBER CS36802FB04
J 0
(-4285 -2650);
DISPLAY 0.638298 (-4285 -2650);
DISPLAY INVISIBLE (-4285 -2650);
FORCEPROP 1 LAST VALUE 68K
J 0
(-4280 -2450);
DISPLAY 0.638298 (-4280 -2450);
FORCEPROP 1 LAST PACK_TYPE 0402LF
J 0
(-4285 -2700);
DISPLAY 0.638298 (-4285 -2700);
FORCEPROP 1 LAST TOLERANCE 1%
J 0
(-4280 -2500);
DISPLAY 0.638298 (-4280 -2500);
FORCEPROP 1 LAST WATTAGE 1/16W
J 0
(-4285 -2550);
DISPLAY 0.638298 (-4285 -2550);
FORCEPROP 1 LAST MATERIAL EMPTY
J 0
(-4285 -2600);
DISPLAY 0.638298 (-4285 -2600);
PAINT RED (-4285 -2600);
FORCEPROP 1 LAST $LOCATION R3268
J 0
(-4280 -2400);
DISPLAY 0.638298 (-4280 -2400);
FORCEPROP 1 LASTPIN (-4325 -2425) $PN 1
J 0
(-4320 -2463);
DISPLAY 0.787234 (-4320 -2463);
PAINT MONO (-4320 -2463);
FORCEPROP 1 LASTPIN (-4325 -2625) $PN 2
J 0
(-4320 -2615);
DISPLAY 0.787234 (-4320 -2615);
PAINT MONO (-4320 -2615);
FORCEPROP 2 LAST CDS_LIB pure_quanta
J 0
(-4325 -2525);
DISPLAY INVISIBLE (-4325 -2525);
FORCEPROP 1 LAST PATH I2
J 0
(-4275 -2350);
DISPLAY 0.978723 (-4275 -2350);
PAINT WHITE (-4275 -2350);
DISPLAY INVISIBLE (-4275 -2350);
FORCEPROP 0 LAST CDS_LOCATION R3268
J 0
(-4275 -2350);
DISPLAY 1.021277 (-4275 -2350);
DISPLAY INVISIBLE (-4275 -2350);
FORCEPROP 0 LAST $SEC 1
J 0
(-4275 -2350);
DISPLAY 0.680851 (-4275 -2350);
PAINT MONO (-4275 -2350);
DISPLAY INVISIBLE (-4275 -2350);
FORCEPROP 0 LAST CDS_SEC 1
J 0
(-4275 -2350);
DISPLAY 1.021277 (-4275 -2350);
DISPLAY INVISIBLE (-4275 -2350);
FORCEADD Q_RES..2
(-3250 -850);
FORCEPROP 1 LAST PART_NUMBER CS21002FB06
J 0
(-3210 -975);
DISPLAY 0.638298 (-3210 -975);
DISPLAY INVISIBLE (-3210 -975);
FORCEPROP 1 LAST PACK_TYPE 0402LF
J 0
(-3210 -1025);
DISPLAY 0.638298 (-3210 -1025);
FORCEPROP 1 LAST VALUE 1K
J 0
(-3205 -775);
DISPLAY 0.638298 (-3205 -775);
FORCEPROP 1 LAST TOLERANCE 1%
J 0
(-3205 -825);
DISPLAY 0.638298 (-3205 -825);
FORCEPROP 1 LAST WATTAGE 1/16W
J 0
(-3210 -875);
DISPLAY 0.638298 (-3210 -875);
FORCEPROP 1 LAST MATERIAL EMPTY
J 0
(-3210 -925);
DISPLAY 0.638298 (-3210 -925);
PAINT RED (-3210 -925);
FORCEPROP 1 LAST $LOCATION R3276
J 0
(-3205 -725);
DISPLAY 0.978723 (-3205 -725);
FORCEPROP 1 LASTPIN (-3250 -750) $PN 1
J 0
(-3245 -788);
DISPLAY 0.787234 (-3245 -788);
PAINT MONO (-3245 -788);
FORCEPROP 1 LASTPIN (-3250 -950) $PN 2
J 0
(-3245 -940);
DISPLAY 0.787234 (-3245 -940);
PAINT MONO (-3245 -940);
FORCEPROP 2 LAST CDS_LIB pure_quanta
J 0
(-3250 -850);
DISPLAY INVISIBLE (-3250 -850);
FORCEPROP 1 LAST PATH I20
J 0
(-3200 -675);
DISPLAY 0.978723 (-3200 -675);
PAINT WHITE (-3200 -675);
DISPLAY INVISIBLE (-3200 -675);
FORCEPROP 0 LAST CDS_LOCATION R3276
J 0
(-3200 -675);
DISPLAY 1.021277 (-3200 -675);
DISPLAY INVISIBLE (-3200 -675);
FORCEPROP 0 LAST $SEC 1
J 0
(-3200 -675);
DISPLAY 0.680851 (-3200 -675);
PAINT MONO (-3200 -675);
DISPLAY INVISIBLE (-3200 -675);
FORCEPROP 0 LAST CDS_SEC 1
J 0
(-3200 -675);
DISPLAY 1.021277 (-3200 -675);
DISPLAY INVISIBLE (-3200 -675);
FORCEADD Q_RES..2
(-3250 -275);
FORCEPROP 1 LAST PART_NUMBER CS21002FB06
J 0
(-3210 -400);
DISPLAY 0.638298 (-3210 -400);
DISPLAY INVISIBLE (-3210 -400);
FORCEPROP 1 LAST WATTAGE 1/16W
J 0
(-3210 -300);
DISPLAY 0.638298 (-3210 -300);
FORCEPROP 1 LAST PACK_TYPE 0402LF
J 0
(-3210 -450);
DISPLAY 0.638298 (-3210 -450);
FORCEPROP 1 LAST MATERIAL EMPTY
J 0
(-3210 -350);
DISPLAY 0.638298 (-3210 -350);
PAINT RED (-3210 -350);
FORCEPROP 1 LAST VALUE 1K
J 0
(-3205 -200);
DISPLAY 0.638298 (-3205 -200);
FORCEPROP 1 LAST TOLERANCE 1%
J 0
(-3205 -250);
DISPLAY 0.638298 (-3205 -250);
FORCEPROP 1 LAST $LOCATION R3275
J 0
(-3205 -150);
DISPLAY 0.978723 (-3205 -150);
FORCEPROP 1 LASTPIN (-3250 -175) $PN 1
J 0
(-3245 -213);
DISPLAY 0.787234 (-3245 -213);
PAINT MONO (-3245 -213);
FORCEPROP 1 LASTPIN (-3250 -375) $PN 2
J 0
(-3245 -365);
DISPLAY 0.787234 (-3245 -365);
PAINT MONO (-3245 -365);
FORCEPROP 2 LAST CDS_LIB pure_quanta
J 0
(-3250 -275);
DISPLAY INVISIBLE (-3250 -275);
FORCEPROP 1 LAST PATH I21
J 0
(-3200 -100);
DISPLAY 0.978723 (-3200 -100);
PAINT WHITE (-3200 -100);
DISPLAY INVISIBLE (-3200 -100);
FORCEPROP 0 LAST CDS_LOCATION R3275
J 0
(-3200 -100);
DISPLAY 1.021277 (-3200 -100);
DISPLAY INVISIBLE (-3200 -100);
FORCEPROP 0 LAST $SEC 1
J 0
(-3200 -100);
DISPLAY 0.680851 (-3200 -100);
PAINT MONO (-3200 -100);
DISPLAY INVISIBLE (-3200 -100);
FORCEPROP 0 LAST CDS_SEC 1
J 0
(-3200 -100);
DISPLAY 1.021277 (-3200 -100);
DISPLAY INVISIBLE (-3200 -100);
FORCEADD UNIVERSAL_GND..1
(-2075 -2900);
FORCEPROP 3 LASTPIN (-2075 -2850) SIG_NAME GND\g
J 0
(-2065 -2840);
DISPLAY 0.659574 (-2065 -2840);
PAINT MONO (-2065 -2840);
DISPLAY INVISIBLE (-2065 -2840);
FORCEPROP 2 LAST ROOM IO_SLOT
J 1
(-2300 -2825);
DISPLAY 0.744681 (-2300 -2825);
DISPLAY INVISIBLE (-2300 -2825);
FORCEPROP 2 LAST CDS_LIB logical_power
J 0
(-2075 -2900);
DISPLAY INVISIBLE (-2075 -2900);
FORCEPROP 1 LAST HDL_POWER GND
J 1
(-2050 -2975);
DISPLAY 0.872340 (-2050 -2975);
PAINT GREEN (-2050 -2975);
DISPLAY INVISIBLE (-2050 -2975);
FORCEPROP 1 LAST PATH I22
J 0
(-2000 -2900);
DISPLAY 0.872340 (-2000 -2900);
PAINT AQUA (-2000 -2900);
DISPLAY INVISIBLE (-2000 -2900);
FORCEADD Q_RES..2
(-2075 -2550);
FORCEPROP 1 LAST PART_NUMBER CS36802FB04
J 0
(-2035 -2675);
DISPLAY 0.638298 (-2035 -2675);
DISPLAY INVISIBLE (-2035 -2675);
FORCEPROP 1 LAST MATERIAL EMPTY
J 0
(-2035 -2625);
DISPLAY 0.638298 (-2035 -2625);
PAINT RED (-2035 -2625);
FORCEPROP 1 LAST PACK_TYPE 0402LF
J 0
(-2035 -2725);
DISPLAY 0.638298 (-2035 -2725);
FORCEPROP 1 LAST VALUE 68K
J 0
(-2030 -2475);
DISPLAY 0.638298 (-2030 -2475);
FORCEPROP 1 LAST WATTAGE 1/16W
J 0
(-2035 -2575);
DISPLAY 0.638298 (-2035 -2575);
FORCEPROP 1 LAST TOLERANCE 1%
J 0
(-2030 -2525);
DISPLAY 0.638298 (-2030 -2525);
FORCEPROP 1 LAST $LOCATION R3279
J 0
(-2030 -2425);
DISPLAY 0.638298 (-2030 -2425);
FORCEPROP 1 LASTPIN (-2075 -2450) $PN 1
J 0
(-2070 -2488);
DISPLAY 0.787234 (-2070 -2488);
PAINT MONO (-2070 -2488);
FORCEPROP 1 LASTPIN (-2075 -2650) $PN 2
J 0
(-2070 -2640);
DISPLAY 0.787234 (-2070 -2640);
PAINT MONO (-2070 -2640);
FORCEPROP 2 LAST CDS_LIB pure_quanta
J 0
(-2075 -2550);
DISPLAY INVISIBLE (-2075 -2550);
FORCEPROP 1 LAST PATH I23
J 0
(-2025 -2375);
DISPLAY 0.978723 (-2025 -2375);
PAINT WHITE (-2025 -2375);
DISPLAY INVISIBLE (-2025 -2375);
FORCEPROP 0 LAST CDS_LOCATION R3279
J 0
(-2025 -2375);
DISPLAY 1.021277 (-2025 -2375);
DISPLAY INVISIBLE (-2025 -2375);
FORCEPROP 0 LAST $SEC 1
J 0
(-2025 -2375);
DISPLAY 0.680851 (-2025 -2375);
PAINT MONO (-2025 -2375);
DISPLAY INVISIBLE (-2025 -2375);
FORCEPROP 0 LAST CDS_SEC 1
J 0
(-2025 -2375);
DISPLAY 1.021277 (-2025 -2375);
DISPLAY INVISIBLE (-2025 -2375);
FORCEADD UNIVERSAL_GND..1
(-1700 -2900);
FORCEPROP 3 LASTPIN (-1700 -2850) SIG_NAME GND\g
J 0
(-1690 -2840);
DISPLAY 0.659574 (-1690 -2840);
PAINT MONO (-1690 -2840);
DISPLAY INVISIBLE (-1690 -2840);
FORCEPROP 2 LAST ROOM IO_SLOT
J 1
(-1925 -2825);
DISPLAY 0.744681 (-1925 -2825);
DISPLAY INVISIBLE (-1925 -2825);
FORCEPROP 2 LAST CDS_LIB logical_power
J 0
(-1700 -2900);
DISPLAY INVISIBLE (-1700 -2900);
FORCEPROP 1 LAST HDL_POWER GND
J 1
(-1675 -2975);
DISPLAY 0.872340 (-1675 -2975);
PAINT GREEN (-1675 -2975);
DISPLAY INVISIBLE (-1675 -2975);
FORCEPROP 1 LAST PATH I24
J 0
(-1625 -2900);
DISPLAY 0.872340 (-1625 -2900);
PAINT AQUA (-1625 -2900);
DISPLAY INVISIBLE (-1625 -2900);
FORCEADD Q_RES..2
(-1700 -2550);
FORCEPROP 1 LAST PART_NUMBER CS21002FB06
J 0
(-1660 -2675);
DISPLAY 0.638298 (-1660 -2675);
DISPLAY INVISIBLE (-1660 -2675);
FORCEPROP 1 LAST MATERIAL EMPTY
J 0
(-1660 -2625);
DISPLAY 0.638298 (-1660 -2625);
PAINT RED (-1660 -2625);
FORCEPROP 1 LAST WATTAGE 1/16W
J 0
(-1660 -2575);
DISPLAY 0.638298 (-1660 -2575);
FORCEPROP 1 LAST PACK_TYPE 0402LF
J 0
(-1660 -2725);
DISPLAY 0.638298 (-1660 -2725);
FORCEPROP 1 LAST TOLERANCE 1%
J 0
(-1655 -2525);
DISPLAY 0.638298 (-1655 -2525);
FORCEPROP 1 LAST VALUE 1K
J 0
(-1655 -2475);
DISPLAY 0.638298 (-1655 -2475);
FORCEPROP 1 LAST $LOCATION R3281
J 0
(-1655 -2425);
DISPLAY 0.978723 (-1655 -2425);
FORCEPROP 1 LASTPIN (-1700 -2450) $PN 1
J 0
(-1695 -2488);
DISPLAY 0.787234 (-1695 -2488);
PAINT MONO (-1695 -2488);
FORCEPROP 1 LASTPIN (-1700 -2650) $PN 2
J 0
(-1695 -2640);
DISPLAY 0.787234 (-1695 -2640);
PAINT MONO (-1695 -2640);
FORCEPROP 2 LAST CDS_LIB pure_quanta
J 0
(-1700 -2550);
DISPLAY INVISIBLE (-1700 -2550);
FORCEPROP 1 LAST PATH I25
J 0
(-1650 -2375);
DISPLAY 0.978723 (-1650 -2375);
PAINT WHITE (-1650 -2375);
DISPLAY INVISIBLE (-1650 -2375);
FORCEPROP 0 LAST CDS_LOCATION R3281
J 0
(-1650 -2375);
DISPLAY 1.021277 (-1650 -2375);
DISPLAY INVISIBLE (-1650 -2375);
FORCEPROP 0 LAST $SEC 1
J 0
(-1650 -2375);
DISPLAY 0.680851 (-1650 -2375);
PAINT MONO (-1650 -2375);
DISPLAY INVISIBLE (-1650 -2375);
FORCEPROP 0 LAST CDS_SEC 1
J 0
(-1650 -2375);
DISPLAY 1.021277 (-1650 -2375);
DISPLAY INVISIBLE (-1650 -2375);
FORCEADD UNIVERSAL_GND..1
(-1225 -2900);
FORCEPROP 3 LASTPIN (-1225 -2850) SIG_NAME GND\g
J 0
(-1215 -2840);
DISPLAY 0.659574 (-1215 -2840);
PAINT MONO (-1215 -2840);
DISPLAY INVISIBLE (-1215 -2840);
FORCEPROP 2 LAST ROOM IO_SLOT
J 1
(-1450 -2825);
DISPLAY 0.744681 (-1450 -2825);
DISPLAY INVISIBLE (-1450 -2825);
FORCEPROP 2 LAST CDS_LIB logical_power
J 0
(-1225 -2900);
DISPLAY INVISIBLE (-1225 -2900);
FORCEPROP 1 LAST HDL_POWER GND
J 1
(-1200 -2975);
DISPLAY 0.872340 (-1200 -2975);
PAINT GREEN (-1200 -2975);
DISPLAY INVISIBLE (-1200 -2975);
FORCEPROP 1 LAST PATH I26
J 0
(-1150 -2900);
DISPLAY 0.872340 (-1150 -2900);
PAINT AQUA (-1150 -2900);
DISPLAY INVISIBLE (-1150 -2900);
FORCEADD Q_RES..2
(-1225 -2575);
FORCEPROP 1 LAST PART_NUMBER CS36802FB04
J 0
(-1185 -2700);
DISPLAY 0.638298 (-1185 -2700);
DISPLAY INVISIBLE (-1185 -2700);
FORCEPROP 1 LAST MATERIAL EMPTY
J 0
(-1185 -2650);
DISPLAY 0.638298 (-1185 -2650);
PAINT RED (-1185 -2650);
FORCEPROP 1 LAST PACK_TYPE 0402LF
J 0
(-1185 -2750);
DISPLAY 0.638298 (-1185 -2750);
FORCEPROP 1 LAST VALUE 68K
J 0
(-1180 -2500);
DISPLAY 0.638298 (-1180 -2500);
FORCEPROP 1 LAST WATTAGE 1/16W
J 0
(-1185 -2600);
DISPLAY 0.638298 (-1185 -2600);
FORCEPROP 1 LAST TOLERANCE 1%
J 0
(-1180 -2550);
DISPLAY 0.638298 (-1180 -2550);
FORCEPROP 1 LAST $LOCATION R3282
J 0
(-1180 -2450);
DISPLAY 0.978723 (-1180 -2450);
FORCEPROP 1 LASTPIN (-1225 -2475) $PN 1
J 0
(-1220 -2513);
DISPLAY 0.787234 (-1220 -2513);
PAINT MONO (-1220 -2513);
FORCEPROP 1 LASTPIN (-1225 -2675) $PN 2
J 0
(-1220 -2665);
DISPLAY 0.787234 (-1220 -2665);
PAINT MONO (-1220 -2665);
FORCEPROP 2 LAST CDS_LIB pure_quanta
J 0
(-1225 -2575);
DISPLAY INVISIBLE (-1225 -2575);
FORCEPROP 1 LAST PATH I27
J 0
(-1175 -2400);
DISPLAY 0.978723 (-1175 -2400);
PAINT WHITE (-1175 -2400);
DISPLAY INVISIBLE (-1175 -2400);
FORCEPROP 0 LAST CDS_LOCATION R3282
J 0
(-1175 -2400);
DISPLAY 1.021277 (-1175 -2400);
DISPLAY INVISIBLE (-1175 -2400);
FORCEPROP 0 LAST $SEC 1
J 0
(-1175 -2400);
DISPLAY 0.680851 (-1175 -2400);
PAINT MONO (-1175 -2400);
DISPLAY INVISIBLE (-1175 -2400);
FORCEPROP 0 LAST CDS_SEC 1
J 0
(-1175 -2400);
DISPLAY 1.021277 (-1175 -2400);
DISPLAY INVISIBLE (-1175 -2400);
FORCEADD OFFPAGE..2
(-2550 -2300);
FORCEPROP 2 LAST $XR0 166 
J 0
(-2361 -2300);
DISPLAY 0.638298 (-2361 -2300);
PAINT MONO (-2361 -2300);
FORCEPROP 2 LAST CDS_LIB standard
J 0
(-2550 -2300);
DISPLAY INVISIBLE (-2550 -2300);
FORCEPROP 1 LAST OFFPAGE TRUE
J 0
(-2225 -2425);
DISPLAY 0.872340 (-2225 -2425);
PAINT GREEN (-2225 -2425);
DISPLAY INVISIBLE (-2225 -2425);
FORCEPROP 1 LAST COMMENT_BODY TRUE
J 0
(-2595 -2395);
DISPLAY 0.872340 (-2595 -2395);
PAINT GREEN (-2595 -2395);
DISPLAY INVISIBLE (-2595 -2395);
FORCEPROP 2 LAST PATH I28
J 0
(-2350 -2250);
DISPLAY 1.021277 (-2350 -2250);
DISPLAY INVISIBLE (-2350 -2250);
FORCEADD OFFPAGE..2
(-2550 -2250);
FORCEPROP 2 LAST $XR0 166 
J 0
(-2361 -2250);
DISPLAY 0.638298 (-2361 -2250);
PAINT MONO (-2361 -2250);
FORCEPROP 2 LAST CDS_LIB standard
J 0
(-2550 -2250);
DISPLAY INVISIBLE (-2550 -2250);
FORCEPROP 1 LAST OFFPAGE TRUE
J 0
(-2225 -2375);
DISPLAY 0.872340 (-2225 -2375);
PAINT GREEN (-2225 -2375);
DISPLAY INVISIBLE (-2225 -2375);
FORCEPROP 1 LAST COMMENT_BODY TRUE
J 0
(-2595 -2345);
DISPLAY 0.872340 (-2595 -2345);
PAINT GREEN (-2595 -2345);
DISPLAY INVISIBLE (-2595 -2345);
FORCEPROP 2 LAST PATH I29
J 0
(-2350 -2200);
DISPLAY 1.021277 (-2350 -2200);
DISPLAY INVISIBLE (-2350 -2200);
FORCEADD UNIVERSAL_GND..1
(-3950 -2875);
FORCEPROP 3 LASTPIN (-3950 -2825) SIG_NAME GND\g
J 0
(-3940 -2815);
DISPLAY 0.659574 (-3940 -2815);
PAINT MONO (-3940 -2815);
DISPLAY INVISIBLE (-3940 -2815);
FORCEPROP 2 LAST ROOM IO_SLOT
J 1
(-4175 -2800);
DISPLAY 0.744681 (-4175 -2800);
DISPLAY INVISIBLE (-4175 -2800);
FORCEPROP 2 LAST CDS_LIB logical_power
J 0
(-3950 -2875);
DISPLAY INVISIBLE (-3950 -2875);
FORCEPROP 1 LAST HDL_POWER GND
J 1
(-3925 -2950);
DISPLAY 0.872340 (-3925 -2950);
PAINT GREEN (-3925 -2950);
DISPLAY INVISIBLE (-3925 -2950);
FORCEPROP 1 LAST PATH I3
J 0
(-3875 -2875);
DISPLAY 0.872340 (-3875 -2875);
PAINT AQUA (-3875 -2875);
DISPLAY INVISIBLE (-3875 -2875);
FORCEADD OFFPAGE..2
(-2800 -575);
FORCEPROP 2 LAST $XR0 166 
J 0
(-2611 -575);
DISPLAY 0.638298 (-2611 -575);
PAINT MONO (-2611 -575);
FORCEPROP 2 LAST CDS_LIB standard
J 0
(-2800 -575);
DISPLAY INVISIBLE (-2800 -575);
FORCEPROP 1 LAST OFFPAGE TRUE
J 0
(-2475 -700);
DISPLAY 0.872340 (-2475 -700);
PAINT GREEN (-2475 -700);
DISPLAY INVISIBLE (-2475 -700);
FORCEPROP 1 LAST COMMENT_BODY TRUE
J 0
(-2845 -670);
DISPLAY 0.872340 (-2845 -670);
PAINT GREEN (-2845 -670);
DISPLAY INVISIBLE (-2845 -670);
FORCEPROP 2 LAST PATH I30
J 0
(-2600 -525);
DISPLAY 1.021277 (-2600 -525);
DISPLAY INVISIBLE (-2600 -525);
FORCEADD OFFPAGE..2
(-2800 -525);
FORCEPROP 2 LAST $XR0 166 
J 0
(-2611 -525);
DISPLAY 0.638298 (-2611 -525);
PAINT MONO (-2611 -525);
FORCEPROP 2 LAST CDS_LIB standard
J 0
(-2800 -525);
DISPLAY INVISIBLE (-2800 -525);
FORCEPROP 1 LAST OFFPAGE TRUE
J 0
(-2475 -650);
DISPLAY 0.872340 (-2475 -650);
PAINT GREEN (-2475 -650);
DISPLAY INVISIBLE (-2475 -650);
FORCEPROP 1 LAST COMMENT_BODY TRUE
J 0
(-2845 -620);
DISPLAY 0.872340 (-2845 -620);
PAINT GREEN (-2845 -620);
DISPLAY INVISIBLE (-2845 -620);
FORCEPROP 2 LAST PATH I31
J 0
(-2600 -475);
DISPLAY 1.021277 (-2600 -475);
DISPLAY INVISIBLE (-2600 -475);
FORCEADD Q_RES..2
(-1700 -2025);
FORCEPROP 1 LAST PART_NUMBER CS21002FB06
J 0
(-1660 -2150);
DISPLAY 0.638298 (-1660 -2150);
DISPLAY INVISIBLE (-1660 -2150);
FORCEPROP 1 LAST VALUE 1K
J 0
(-1655 -1950);
DISPLAY 0.638298 (-1655 -1950);
FORCEPROP 1 LAST MATERIAL EMPTY
J 0
(-1660 -2100);
DISPLAY 0.638298 (-1660 -2100);
PAINT RED (-1660 -2100);
FORCEPROP 1 LAST TOLERANCE 1%
J 0
(-1655 -2000);
DISPLAY 0.638298 (-1655 -2000);
FORCEPROP 1 LAST WATTAGE 1/16W
J 0
(-1660 -2050);
DISPLAY 0.638298 (-1660 -2050);
FORCEPROP 1 LAST PACK_TYPE 0402LF
J 0
(-1660 -2200);
DISPLAY 0.638298 (-1660 -2200);
FORCEPROP 1 LAST $LOCATION R3280
J 0
(-1655 -1900);
DISPLAY 0.638298 (-1655 -1900);
FORCEPROP 1 LASTPIN (-1700 -1925) $PN 1
J 0
(-1695 -1963);
DISPLAY 0.787234 (-1695 -1963);
PAINT MONO (-1695 -1963);
FORCEPROP 1 LASTPIN (-1700 -2125) $PN 2
J 0
(-1695 -2115);
DISPLAY 0.787234 (-1695 -2115);
PAINT MONO (-1695 -2115);
FORCEPROP 2 LAST CDS_LIB pure_quanta
J 0
(-1700 -2025);
DISPLAY INVISIBLE (-1700 -2025);
FORCEPROP 1 LAST PATH I32
J 0
(-1650 -1850);
DISPLAY 0.978723 (-1650 -1850);
PAINT WHITE (-1650 -1850);
DISPLAY INVISIBLE (-1650 -1850);
FORCEPROP 0 LAST CDS_LOCATION R3280
J 0
(-1650 -1850);
DISPLAY 1.021277 (-1650 -1850);
DISPLAY INVISIBLE (-1650 -1850);
FORCEPROP 0 LAST $SEC 1
J 0
(-1650 -1850);
DISPLAY 0.680851 (-1650 -1850);
PAINT MONO (-1650 -1850);
DISPLAY INVISIBLE (-1650 -1850);
FORCEPROP 0 LAST CDS_SEC 1
J 0
(-1650 -1850);
DISPLAY 1.021277 (-1650 -1850);
DISPLAY INVISIBLE (-1650 -1850);
FORCEADD UNIVERSAL_POWER..1
(-1700 -1725);
FORCEPROP 3 LASTPIN (-1700 -1775) SIG_NAME P3V3_AUX\g
J 0
(-1690 -1765);
DISPLAY 0.659574 (-1690 -1765);
PAINT MONO (-1690 -1765);
DISPLAY INVISIBLE (-1690 -1765);
FORCEPROP 1 LAST HDL_POWER P3V3_AUX
J 1
(-1700 -1675);
DISPLAY 0.872340 (-1700 -1675);
PAINT GREEN (-1700 -1675);
FORCEPROP 2 LAST CDS_LIB logical_power
J 0
(-1700 -1725);
DISPLAY INVISIBLE (-1700 -1725);
FORCEPROP 1 LAST PATH I33
J 0
(-1650 -1700);
DISPLAY 0.872340 (-1650 -1700);
PAINT AQUA (-1650 -1700);
DISPLAY INVISIBLE (-1650 -1700);
FORCEADD UNIVERSAL_POWER..1
(-4125 25);
FORCEPROP 3 LASTPIN (-4125 -25) SIG_NAME P3V3_AUX\g
J 0
(-4115 -15);
DISPLAY 0.659574 (-4115 -15);
PAINT MONO (-4115 -15);
DISPLAY INVISIBLE (-4115 -15);
FORCEPROP 1 LAST HDL_POWER P3V3_AUX
J 1
(-4125 75);
DISPLAY 0.872340 (-4125 75);
PAINT GREEN (-4125 75);
FORCEPROP 2 LAST CDS_LIB logical_power
J 0
(-4125 25);
DISPLAY INVISIBLE (-4125 25);
FORCEPROP 1 LAST PATH I34
J 0
(-4075 50);
DISPLAY 0.872340 (-4075 50);
PAINT AQUA (-4075 50);
DISPLAY INVISIBLE (-4075 50);
FORCEADD OFFPAGE..4
R 2
(-3000 1100);
FORCEPROP 2 LAST $XR0 167 
J 0
(-3252 1100);
DISPLAY 0.638298 (-3252 1100);
PAINT MONO (-3252 1100);
FORCEPROP 2 LAST CDS_LIB standard
J 0
(-3000 1100);
DISPLAY INVISIBLE (-3000 1100);
FORCEPROP 1 LAST OFFPAGE TRUE
J 2
(-3325 975);
DISPLAY 0.872340 (-3325 975);
PAINT GREEN (-3325 975);
DISPLAY INVISIBLE (-3325 975);
FORCEPROP 1 LAST COMMENT_BODY TRUE
J 2
(-2975 1000);
DISPLAY 0.872340 (-2975 1000);
PAINT GREEN (-2975 1000);
DISPLAY INVISIBLE (-2975 1000);
FORCEPROP 2 LAST PATH I35
J 0
(-3250 1150);
DISPLAY 1.021277 (-3250 1150);
DISPLAY INVISIBLE (-3250 1150);
FORCEADD OFFPAGE..4
R 2
(-3000 1050);
FORCEPROP 2 LAST $XR0 167 
J 0
(-3252 1050);
DISPLAY 0.638298 (-3252 1050);
PAINT MONO (-3252 1050);
FORCEPROP 2 LAST CDS_LIB standard
J 2
(-3000 1050);
DISPLAY INVISIBLE (-3000 1050);
FORCEPROP 1 LAST OFFPAGE TRUE
J 2
(-3325 925);
DISPLAY 0.872340 (-3325 925);
PAINT GREEN (-3325 925);
DISPLAY INVISIBLE (-3325 925);
FORCEPROP 1 LAST COMMENT_BODY TRUE
J 2
(-2975 950);
DISPLAY 0.872340 (-2975 950);
PAINT GREEN (-2975 950);
DISPLAY INVISIBLE (-2975 950);
FORCEPROP 2 LAST PATH I36
J 0
(-3250 1100);
DISPLAY 1.021277 (-3250 1100);
DISPLAY INVISIBLE (-3250 1100);
FORCEADD OFFPAGE..4
R 2
(-3000 1200);
FORCEPROP 2 LAST $XR0 167 
J 0
(-3252 1200);
DISPLAY 0.638298 (-3252 1200);
PAINT MONO (-3252 1200);
FORCEPROP 2 LAST CDS_LIB standard
J 0
(-3000 1200);
DISPLAY INVISIBLE (-3000 1200);
FORCEPROP 1 LAST OFFPAGE TRUE
J 2
(-3325 1075);
DISPLAY 0.872340 (-3325 1075);
PAINT GREEN (-3325 1075);
DISPLAY INVISIBLE (-3325 1075);
FORCEPROP 1 LAST COMMENT_BODY TRUE
J 2
(-2975 1100);
DISPLAY 0.872340 (-2975 1100);
PAINT GREEN (-2975 1100);
DISPLAY INVISIBLE (-2975 1100);
FORCEPROP 2 LAST PATH I37
J 0
(-3250 1250);
DISPLAY 1.021277 (-3250 1250);
DISPLAY INVISIBLE (-3250 1250);
FORCEADD OFFPAGE..4
R 2
(-3000 1350);
FORCEPROP 2 LAST $XR0 166 
J 0
(-3252 1350);
DISPLAY 0.638298 (-3252 1350);
PAINT MONO (-3252 1350);
FORCEPROP 2 LAST CDS_LIB standard
J 0
(-3000 1350);
DISPLAY INVISIBLE (-3000 1350);
FORCEPROP 1 LAST OFFPAGE TRUE
J 2
(-3325 1225);
DISPLAY 0.872340 (-3325 1225);
PAINT GREEN (-3325 1225);
DISPLAY INVISIBLE (-3325 1225);
FORCEPROP 1 LAST COMMENT_BODY TRUE
J 2
(-2975 1250);
DISPLAY 0.872340 (-2975 1250);
PAINT GREEN (-2975 1250);
DISPLAY INVISIBLE (-2975 1250);
FORCEPROP 2 LAST PATH I38
J 0
(-3250 1400);
DISPLAY 1.021277 (-3250 1400);
DISPLAY INVISIBLE (-3250 1400);
FORCEADD OFFPAGE..4
R 2
(-3000 1400);
FORCEPROP 2 LAST $XR0 166 
J 0
(-3252 1400);
DISPLAY 0.638298 (-3252 1400);
PAINT MONO (-3252 1400);
FORCEPROP 2 LAST CDS_LIB standard
J 0
(-3000 1400);
DISPLAY INVISIBLE (-3000 1400);
FORCEPROP 1 LAST OFFPAGE TRUE
J 2
(-3325 1275);
DISPLAY 0.872340 (-3325 1275);
PAINT GREEN (-3325 1275);
DISPLAY INVISIBLE (-3325 1275);
FORCEPROP 1 LAST COMMENT_BODY TRUE
J 2
(-2975 1300);
DISPLAY 0.872340 (-2975 1300);
PAINT GREEN (-2975 1300);
DISPLAY INVISIBLE (-2975 1300);
FORCEPROP 2 LAST PATH I39
J 0
(-3250 1450);
DISPLAY 1.021277 (-3250 1450);
DISPLAY INVISIBLE (-3250 1450);
FORCEADD Q_RES..2
(-3950 -2525);
FORCEPROP 1 LAST PART_NUMBER CS21002FB06
J 0
(-3910 -2650);
DISPLAY 0.638298 (-3910 -2650);
DISPLAY INVISIBLE (-3910 -2650);
FORCEPROP 1 LAST MATERIAL EMPTY
J 0
(-3910 -2600);
DISPLAY 0.638298 (-3910 -2600);
PAINT RED (-3910 -2600);
FORCEPROP 1 LAST WATTAGE 1/16W
J 0
(-3910 -2550);
DISPLAY 0.638298 (-3910 -2550);
FORCEPROP 1 LAST VALUE 1K
J 0
(-3905 -2450);
DISPLAY 0.638298 (-3905 -2450);
FORCEPROP 1 LAST TOLERANCE 1%
J 0
(-3905 -2500);
DISPLAY 0.638298 (-3905 -2500);
FORCEPROP 1 LAST PACK_TYPE 0402LF
J 0
(-3910 -2700);
DISPLAY 0.638298 (-3910 -2700);
FORCEPROP 1 LAST $LOCATION R3272
J 0
(-3905 -2400);
DISPLAY 0.978723 (-3905 -2400);
FORCEPROP 1 LASTPIN (-3950 -2425) $PN 1
J 0
(-3945 -2463);
DISPLAY 0.787234 (-3945 -2463);
PAINT MONO (-3945 -2463);
FORCEPROP 1 LASTPIN (-3950 -2625) $PN 2
J 0
(-3945 -2615);
DISPLAY 0.787234 (-3945 -2615);
PAINT MONO (-3945 -2615);
FORCEPROP 2 LAST CDS_LIB pure_quanta
J 0
(-3950 -2525);
DISPLAY INVISIBLE (-3950 -2525);
FORCEPROP 1 LAST PATH I4
J 0
(-3900 -2350);
DISPLAY 0.978723 (-3900 -2350);
PAINT WHITE (-3900 -2350);
DISPLAY INVISIBLE (-3900 -2350);
FORCEPROP 0 LAST CDS_LOCATION R3272
J 0
(-3900 -2350);
DISPLAY 1.021277 (-3900 -2350);
DISPLAY INVISIBLE (-3900 -2350);
FORCEPROP 0 LAST $SEC 1
J 0
(-3900 -2350);
DISPLAY 0.680851 (-3900 -2350);
PAINT MONO (-3900 -2350);
DISPLAY INVISIBLE (-3900 -2350);
FORCEPROP 0 LAST CDS_SEC 1
J 0
(-3900 -2350);
DISPLAY 1.021277 (-3900 -2350);
DISPLAY INVISIBLE (-3900 -2350);
FORCEADD OFFPAGE..4
R 2
(-3000 1500);
FORCEPROP 2 LAST $XR0 166 
J 0
(-3252 1500);
DISPLAY 0.638298 (-3252 1500);
PAINT MONO (-3252 1500);
FORCEPROP 2 LAST CDS_LIB standard
J 0
(-3000 1500);
DISPLAY INVISIBLE (-3000 1500);
FORCEPROP 1 LAST OFFPAGE TRUE
J 2
(-3325 1375);
DISPLAY 0.872340 (-3325 1375);
PAINT GREEN (-3325 1375);
DISPLAY INVISIBLE (-3325 1375);
FORCEPROP 1 LAST COMMENT_BODY TRUE
J 2
(-2975 1400);
DISPLAY 0.872340 (-2975 1400);
PAINT GREEN (-2975 1400);
DISPLAY INVISIBLE (-2975 1400);
FORCEPROP 2 LAST PATH I40
J 0
(-3250 1550);
DISPLAY 1.021277 (-3250 1550);
DISPLAY INVISIBLE (-3250 1550);
FORCEADD OFFPAGE..4
R 2
(-3000 1550);
FORCEPROP 2 LAST $XR0 166 
J 0
(-3252 1550);
DISPLAY 0.638298 (-3252 1550);
PAINT MONO (-3252 1550);
FORCEPROP 2 LAST CDS_LIB standard
J 0
(-3000 1550);
DISPLAY INVISIBLE (-3000 1550);
FORCEPROP 1 LAST OFFPAGE TRUE
J 2
(-3325 1425);
DISPLAY 0.872340 (-3325 1425);
PAINT GREEN (-3325 1425);
DISPLAY INVISIBLE (-3325 1425);
FORCEPROP 1 LAST COMMENT_BODY TRUE
J 2
(-2975 1450);
DISPLAY 0.872340 (-2975 1450);
PAINT GREEN (-2975 1450);
DISPLAY INVISIBLE (-2975 1450);
FORCEPROP 2 LAST PATH I41
J 0
(-3250 1600);
DISPLAY 1.021277 (-3250 1600);
DISPLAY INVISIBLE (-3250 1600);
FORCEADD OFFPAGE..4
R 2
(-3000 1650);
FORCEPROP 2 LAST $XR0 166 
J 0
(-3252 1650);
DISPLAY 0.638298 (-3252 1650);
PAINT MONO (-3252 1650);
FORCEPROP 2 LAST CDS_LIB standard
J 0
(-3000 1650);
DISPLAY INVISIBLE (-3000 1650);
FORCEPROP 1 LAST OFFPAGE TRUE
J 2
(-3325 1525);
DISPLAY 0.872340 (-3325 1525);
PAINT GREEN (-3325 1525);
DISPLAY INVISIBLE (-3325 1525);
FORCEPROP 1 LAST COMMENT_BODY TRUE
J 2
(-2975 1550);
DISPLAY 0.872340 (-2975 1550);
PAINT GREEN (-2975 1550);
DISPLAY INVISIBLE (-2975 1550);
FORCEPROP 2 LAST PATH I42
J 0
(-3250 1700);
DISPLAY 1.021277 (-3250 1700);
DISPLAY INVISIBLE (-3250 1700);
FORCEADD OFFPAGE..4
R 2
(-3000 1250);
FORCEPROP 2 LAST $XR0 167 
J 0
(-3252 1250);
DISPLAY 0.638298 (-3252 1250);
PAINT MONO (-3252 1250);
FORCEPROP 2 LAST CDS_LIB standard
J 0
(-3000 1250);
DISPLAY INVISIBLE (-3000 1250);
FORCEPROP 1 LAST OFFPAGE TRUE
J 2
(-3325 1125);
DISPLAY 0.872340 (-3325 1125);
PAINT GREEN (-3325 1125);
DISPLAY INVISIBLE (-3325 1125);
FORCEPROP 1 LAST COMMENT_BODY TRUE
J 2
(-2975 1150);
DISPLAY 0.872340 (-2975 1150);
PAINT GREEN (-2975 1150);
DISPLAY INVISIBLE (-2975 1150);
FORCEPROP 2 LAST PATH I43
J 0
(-3250 1300);
DISPLAY 1.021277 (-3250 1300);
DISPLAY INVISIBLE (-3250 1300);
FORCEADD OFFPAGE..4
R 2
(-3000 1700);
FORCEPROP 2 LAST $XR0 166 
J 0
(-3252 1700);
DISPLAY 0.638298 (-3252 1700);
PAINT MONO (-3252 1700);
FORCEPROP 2 LAST CDS_LIB standard
J 0
(-3000 1700);
DISPLAY INVISIBLE (-3000 1700);
FORCEPROP 1 LAST OFFPAGE TRUE
J 2
(-3325 1575);
DISPLAY 0.872340 (-3325 1575);
PAINT GREEN (-3325 1575);
DISPLAY INVISIBLE (-3325 1575);
FORCEPROP 1 LAST COMMENT_BODY TRUE
J 2
(-2975 1600);
DISPLAY 0.872340 (-2975 1600);
PAINT GREEN (-2975 1600);
DISPLAY INVISIBLE (-2975 1600);
FORCEPROP 2 LAST PATH I44
J 0
(-3250 1750);
DISPLAY 1.021277 (-3250 1750);
DISPLAY INVISIBLE (-3250 1750);
FORCEADD OFFPAGE..4
R 2
(-3000 1900);
FORCEPROP 2 LAST $XR0 166 
J 0
(-3252 1900);
DISPLAY 0.638298 (-3252 1900);
PAINT MONO (-3252 1900);
FORCEPROP 2 LAST CDS_LIB standard
J 0
(-3000 1900);
DISPLAY INVISIBLE (-3000 1900);
FORCEPROP 1 LAST OFFPAGE TRUE
J 2
(-3325 1775);
DISPLAY 0.872340 (-3325 1775);
PAINT GREEN (-3325 1775);
DISPLAY INVISIBLE (-3325 1775);
FORCEPROP 1 LAST COMMENT_BODY TRUE
J 2
(-2975 1800);
DISPLAY 0.872340 (-2975 1800);
PAINT GREEN (-2975 1800);
DISPLAY INVISIBLE (-2975 1800);
FORCEPROP 2 LAST PATH I45
J 0
(-3250 1950);
DISPLAY 1.021277 (-3250 1950);
DISPLAY INVISIBLE (-3250 1950);
FORCEADD OFFPAGE..4
R 2
(-3000 1850);
FORCEPROP 2 LAST $XR0 166 
J 0
(-3252 1850);
DISPLAY 0.638298 (-3252 1850);
PAINT MONO (-3252 1850);
FORCEPROP 2 LAST CDS_LIB standard
J 0
(-3000 1850);
DISPLAY INVISIBLE (-3000 1850);
FORCEPROP 1 LAST OFFPAGE TRUE
J 2
(-3325 1725);
DISPLAY 0.872340 (-3325 1725);
PAINT GREEN (-3325 1725);
DISPLAY INVISIBLE (-3325 1725);
FORCEPROP 1 LAST COMMENT_BODY TRUE
J 2
(-2975 1750);
DISPLAY 0.872340 (-2975 1750);
PAINT GREEN (-2975 1750);
DISPLAY INVISIBLE (-2975 1750);
FORCEPROP 2 LAST PATH I46
J 0
(-3250 1900);
DISPLAY 1.021277 (-3250 1900);
DISPLAY INVISIBLE (-3250 1900);
FORCEADD UNIVERSAL_GND..1
(-3275 2000);
FORCEPROP 3 LASTPIN (-3275 2050) SIG_NAME GND\g
J 0
(-3265 2060);
DISPLAY 0.659574 (-3265 2060);
PAINT MONO (-3265 2060);
DISPLAY INVISIBLE (-3265 2060);
FORCEPROP 2 LAST CDS_LIB logical_power
J 0
(-3275 2000);
DISPLAY INVISIBLE (-3275 2000);
FORCEPROP 1 LAST HDL_POWER GND
J 1
(-3250 1925);
DISPLAY 0.872340 (-3250 1925);
PAINT GREEN (-3250 1925);
DISPLAY INVISIBLE (-3250 1925);
FORCEPROP 1 LAST PATH I47
J 0
(-3200 2000);
DISPLAY 0.872340 (-3200 2000);
PAINT AQUA (-3200 2000);
DISPLAY INVISIBLE (-3200 2000);
FORCEADD Q_CAP..1
(-3275 2350);
FORCEPROP 1 LAST PART_NUMBER CH6104KEA00
J 0
(-3225 2200);
DISPLAY 0.638298 (-3225 2200);
DISPLAY INVISIBLE (-3225 2200);
FORCEPROP 1 LAST PACK_TYPE C0805
J 0
(-3225 2150);
DISPLAY 0.638298 (-3225 2150);
FORCEPROP 1 LAST MATERIAL X6S
J 0
(-3225 2250);
DISPLAY 0.638298 (-3225 2250);
FORCEPROP 1 LAST TOLERANCE 10%
J 0
(-3225 2300);
DISPLAY 0.638298 (-3225 2300);
FORCEPROP 1 LAST VOLTAGE 25V
J 0
(-3225 2350);
DISPLAY 0.638298 (-3225 2350);
FORCEPROP 1 LAST VALUE 10UF
J 0
(-3225 2400);
DISPLAY 0.638298 (-3225 2400);
FORCEPROP 2 LAST ROOM PCIE REDRIVER1_BOM1
J 0
(-3225 2500);
DISPLAY 0.510638 (-3225 2500);
FORCEPROP 1 LAST $LOCATION C1867
J 0
(-3225 2450);
DISPLAY 0.978723 (-3225 2450);
FORCEPROP 1 LASTPIN (-3275 2450) $PN 1
J 0
(-3265 2430);
DISPLAY 0.787234 (-3265 2430);
PAINT MONO (-3265 2430);
FORCEPROP 1 LASTPIN (-3275 2250) $PN 2
J 0
(-3265 2230);
DISPLAY 0.787234 (-3265 2230);
PAINT MONO (-3265 2230);
FORCEPROP 2 LAST CDS_LIB pure_quanta
J 0
(-3275 2350);
DISPLAY INVISIBLE (-3275 2350);
FORCEPROP 1 LAST PATH I48
J 0
(-3225 2500);
DISPLAY 0.978723 (-3225 2500);
PAINT WHITE (-3225 2500);
DISPLAY INVISIBLE (-3225 2500);
FORCEPROP 0 LAST CDS_LOCATION C1867
J 0
(-3225 2500);
DISPLAY 1.021277 (-3225 2500);
DISPLAY INVISIBLE (-3225 2500);
FORCEPROP 0 LAST $SEC 1
J 0
(-3225 2500);
DISPLAY 0.680851 (-3225 2500);
PAINT MONO (-3225 2500);
DISPLAY INVISIBLE (-3225 2500);
FORCEPROP 0 LAST CDS_SEC 1
J 0
(-3225 2500);
DISPLAY 1.021277 (-3225 2500);
DISPLAY INVISIBLE (-3225 2500);
FORCEADD Q_CAP..1
(-2900 2350);
FORCEPROP 1 LAST PART_NUMBER CH4104K1B00
J 0
(-2850 2200);
DISPLAY 0.808511 (-2850 2200);
DISPLAY INVISIBLE (-2850 2200);
FORCEPROP 1 LAST VOLTAGE 25V
J 0
(-2850 2350);
DISPLAY 0.638298 (-2850 2350);
FORCEPROP 1 LAST TOLERANCE 10%
J 0
(-2850 2300);
DISPLAY 0.638298 (-2850 2300);
FORCEPROP 1 LAST MATERIAL X7R
J 0
(-2850 2250);
DISPLAY 0.638298 (-2850 2250);
FORCEPROP 1 LAST PACK_TYPE 0402
J 0
(-2850 2200);
DISPLAY 0.638298 (-2850 2200);
FORCEPROP 1 LAST VALUE 0.1UF
J 0
(-2850 2400);
DISPLAY 0.638298 (-2850 2400);
FORCEPROP 2 LAST ROOM PCIE REDRIVER1_BOM1
J 0
(-2900 2525);
DISPLAY 0.404255 (-2900 2525);
FORCEPROP 1 LAST $LOCATION C1863
J 0
(-2850 2450);
DISPLAY 0.787234 (-2850 2450);
FORCEPROP 1 LASTPIN (-2900 2450) $PN 1
J 0
(-2890 2430);
DISPLAY 0.787234 (-2890 2430);
FORCEPROP 1 LASTPIN (-2900 2250) $PN 2
J 0
(-2890 2230);
DISPLAY 0.787234 (-2890 2230);
FORCEPROP 2 LAST CDS_LIB pure_quanta
J 0
(-2900 2350);
PAINT MONO (-2900 2350);
DISPLAY INVISIBLE (-2900 2350);
FORCEPROP 1 LAST PATH I49
J 0
(-2850 2500);
DISPLAY 0.978723 (-2850 2500);
PAINT WHITE (-2850 2500);
DISPLAY INVISIBLE (-2850 2500);
FORCEPROP 2 LAST CDS_LOCATION C1863
J 0
(-2850 2550);
DISPLAY 1.021277 (-2850 2550);
DISPLAY INVISIBLE (-2850 2550);
FORCEPROP 2 LAST $SEC 1
J 0
(-2850 2550);
DISPLAY 0.680851 (-2850 2550);
PAINT MONO (-2850 2550);
DISPLAY INVISIBLE (-2850 2550);
FORCEPROP 2 LAST CDS_SEC 1
J 0
(-2850 2550);
DISPLAY 1.021277 (-2850 2550);
DISPLAY INVISIBLE (-2850 2550);
FORCEADD UNIVERSAL_GND..1
(-3475 -2875);
FORCEPROP 3 LASTPIN (-3475 -2825) SIG_NAME GND\g
J 0
(-3465 -2815);
DISPLAY 0.659574 (-3465 -2815);
PAINT MONO (-3465 -2815);
DISPLAY INVISIBLE (-3465 -2815);
FORCEPROP 2 LAST ROOM IO_SLOT
J 1
(-3700 -2800);
DISPLAY 0.744681 (-3700 -2800);
DISPLAY INVISIBLE (-3700 -2800);
FORCEPROP 2 LAST CDS_LIB logical_power
J 0
(-3475 -2875);
DISPLAY INVISIBLE (-3475 -2875);
FORCEPROP 1 LAST HDL_POWER GND
J 1
(-3450 -2950);
DISPLAY 0.872340 (-3450 -2950);
PAINT GREEN (-3450 -2950);
DISPLAY INVISIBLE (-3450 -2950);
FORCEPROP 1 LAST PATH I5
J 0
(-3400 -2875);
DISPLAY 0.872340 (-3400 -2875);
PAINT AQUA (-3400 -2875);
DISPLAY INVISIBLE (-3400 -2875);
FORCEADD PI3EQX12902AZLEX..1
(-1300 1525);
FORCEPROP 1 LAST PART_NUMBER AL012902001
J 0
(-1595 2410);
DISPLAY 0.723404 (-1595 2410);
PAINT GREEN (-1595 2410);
DISPLAY INVISIBLE (-1595 2410);
FORCEPROP 2 LAST VALUE PI3EQX12902AZLEX
J 0
(-1575 2575);
DISPLAY 1.021277 (-1575 2575);
FORCEPROP 2 LAST PART_TYPE SMLF
J 0
(-1575 2625);
DISPLAY 1.021277 (-1575 2625);
FORCEPROP 1 LAST MATERIAL IC
J 0
(-1595 2307);
DISPLAY 0.723404 (-1595 2307);
PAINT GREEN (-1595 2307);
FORCEPROP 2 LAST ROOM PCIE REDRIVER1_BOM1
J 0
(-1575 2675);
DISPLAY 1.021277 (-1575 2675);
FORCEPROP 1 LAST $LOCATION U237
J 0
(-1595 2521);
DISPLAY 0.723404 (-1595 2521);
PAINT GREEN (-1595 2521);
FORCEPROP 0 LASTPIN (-1750 1200) $PN 3
J 2
(-1760 1210);
DISPLAY 0.680851 (-1760 1210);
PAINT MONO (-1760 1210);
FORCEPROP 0 LASTPIN (-1750 1250) $PN 2
J 2
(-1760 1260);
DISPLAY 0.680851 (-1760 1260);
PAINT MONO (-1760 1260);
FORCEPROP 0 LASTPIN (-850 2150) $PN 23
J 0
(-840 2160);
DISPLAY 0.680851 (-840 2160);
PAINT MONO (-840 2160);
FORCEPROP 0 LASTPIN (-850 2200) $PN 24
J 0
(-840 2210);
DISPLAY 0.680851 (-840 2210);
PAINT MONO (-840 2210);
FORCEPROP 0 LASTPIN (-1750 1050) $PN 18
J 2
(-1760 1060);
DISPLAY 0.680851 (-1760 1060);
PAINT MONO (-1760 1060);
FORCEPROP 0 LASTPIN (-1750 1100) $PN 17
J 2
(-1760 1110);
DISPLAY 0.680851 (-1760 1110);
PAINT MONO (-1760 1110);
FORCEPROP 0 LASTPIN (-850 1950) $PN 8
J 0
(-840 1960);
DISPLAY 0.680851 (-840 1960);
PAINT MONO (-840 1960);
FORCEPROP 0 LASTPIN (-850 2000) $PN 9
J 0
(-840 2010);
DISPLAY 0.680851 (-840 2010);
PAINT MONO (-840 2010);
FORCEPROP 0 LASTPIN (-850 1500) $PN 11
J 0
(-840 1510);
DISPLAY 0.680851 (-840 1510);
PAINT MONO (-840 1510);
FORCEPROP 0 LASTPIN (-1750 1550) $PN 21
J 2
(-1760 1560);
DISPLAY 0.680851 (-1760 1560);
PAINT MONO (-1760 1560);
FORCEPROP 0 LASTPIN (-1750 1500) $PN 26
J 2
(-1760 1510);
DISPLAY 0.680851 (-1760 1510);
PAINT MONO (-1760 1510);
FORCEPROP 0 LASTPIN (-1750 1400) $PN 20
J 2
(-1760 1410);
DISPLAY 0.680851 (-1760 1410);
PAINT MONO (-1760 1410);
FORCEPROP 0 LASTPIN (-1750 1350) $PN 15
J 2
(-1760 1360);
DISPLAY 0.680851 (-1760 1360);
PAINT MONO (-1760 1360);
FORCEPROP 0 LASTPIN (-1750 1900) $PN 27
J 2
(-1760 1910);
DISPLAY 0.680851 (-1760 1910);
PAINT MONO (-1760 1910);
FORCEPROP 0 LASTPIN (-1750 1850) $PN 14
J 2
(-1760 1860);
DISPLAY 0.680851 (-1760 1860);
PAINT MONO (-1760 1860);
FORCEPROP 0 LASTPIN (-850 1350) $PN 4
J 0
(-840 1360);
DISPLAY 0.680851 (-840 1360);
PAINT MONO (-840 1360);
FORCEPROP 0 LASTPIN (-850 1300) $PN 6
J 0
(-840 1310);
DISPLAY 0.680851 (-840 1310);
PAINT MONO (-840 1310);
FORCEPROP 0 LASTPIN (-850 1250) $PN 7
J 0
(-840 1260);
DISPLAY 0.680851 (-840 1260);
PAINT MONO (-840 1260);
FORCEPROP 0 LASTPIN (-850 1200) $PN 13
J 0
(-840 1210);
DISPLAY 0.680851 (-840 1210);
PAINT MONO (-840 1210);
FORCEPROP 0 LASTPIN (-850 1150) $PN 19
J 0
(-840 1160);
DISPLAY 0.680851 (-840 1160);
PAINT MONO (-840 1160);
FORCEPROP 0 LASTPIN (-850 1100) $PN 22
J 0
(-840 1110);
DISPLAY 0.680851 (-840 1110);
PAINT MONO (-840 1110);
FORCEPROP 0 LASTPIN (-850 1050) $PN 28
J 0
(-840 1060);
DISPLAY 0.680851 (-840 1060);
PAINT MONO (-840 1060);
FORCEPROP 0 LASTPIN (-850 850) $PN TH
J 0
(-840 860);
DISPLAY 0.680851 (-840 860);
PAINT MONO (-840 860);
FORCEPROP 0 LASTPIN (-850 1800) $PN 30
J 0
(-840 1810);
DISPLAY 0.680851 (-840 1810);
PAINT MONO (-840 1810);
FORCEPROP 0 LASTPIN (-1750 1700) $PN 29
J 2
(-1760 1710);
DISPLAY 0.680851 (-1760 1710);
PAINT MONO (-1760 1710);
FORCEPROP 0 LASTPIN (-1750 1650) $PN 12
J 2
(-1760 1660);
DISPLAY 0.680851 (-1760 1660);
PAINT MONO (-1760 1660);
FORCEPROP 0 LASTPIN (-850 1650) $PN 5
J 0
(-840 1660);
DISPLAY 0.680851 (-840 1660);
PAINT MONO (-840 1660);
FORCEPROP 0 LASTPIN (-1750 2200) $PN 1
J 2
(-1760 2210);
DISPLAY 0.680851 (-1760 2210);
PAINT MONO (-1760 2210);
FORCEPROP 0 LASTPIN (-1750 2150) $PN 10
J 2
(-1760 2160);
DISPLAY 0.680851 (-1760 2160);
PAINT MONO (-1760 2160);
FORCEPROP 0 LASTPIN (-1750 2100) $PN 16
J 2
(-1760 2110);
DISPLAY 0.680851 (-1760 2110);
PAINT MONO (-1760 2110);
FORCEPROP 0 LASTPIN (-1750 2050) $PN 25
J 2
(-1760 2060);
DISPLAY 0.680851 (-1760 2060);
PAINT MONO (-1760 2060);
FORCEPROP 1 LAST NEEDS_NO_SIZE TRUE
J 0
(-1300 1525);
DISPLAY 0.723404 (-1300 1525);
PAINT GREEN (-1300 1525);
DISPLAY INVISIBLE (-1300 1525);
FORCEPROP 1 LAST CDS_LMAN_SYM_OUTLINE -300,775,300,-775
J 0
(-1300 1525);
DISPLAY 0.468085 (-1300 1525);
PAINT GREEN (-1300 1525);
DISPLAY INVISIBLE (-1300 1525);
FORCEPROP 2 LAST CDS_LIB pure_quanta
J 0
(-1300 1525);
DISPLAY INVISIBLE (-1300 1525);
FORCEPROP 1 LAST PATH I50
J 0
(-1300 1525);
DISPLAY 0.723404 (-1300 1525);
PAINT GREEN (-1300 1525);
DISPLAY INVISIBLE (-1300 1525);
FORCEPROP 0 LAST CDS_LOCATION U237
J 0
(-1575 2675);
DISPLAY 1.021277 (-1575 2675);
DISPLAY INVISIBLE (-1575 2675);
FORCEPROP 0 LAST $SEC 1
J 0
(-1575 2675);
DISPLAY 0.680851 (-1575 2675);
PAINT MONO (-1575 2675);
DISPLAY INVISIBLE (-1575 2675);
FORCEPROP 0 LAST CDS_SEC 1
J 0
(-1575 2675);
DISPLAY 1.021277 (-1575 2675);
DISPLAY INVISIBLE (-1575 2675);
FORCEADD Q_CAP..1
(-2625 2350);
FORCEPROP 1 LAST PART_NUMBER CH4104K1B00
J 0
(-2575 2200);
DISPLAY 0.808511 (-2575 2200);
DISPLAY INVISIBLE (-2575 2200);
FORCEPROP 1 LAST MATERIAL X7R
J 0
(-2575 2250);
DISPLAY 0.638298 (-2575 2250);
FORCEPROP 1 LAST VALUE 0.1UF
J 0
(-2575 2400);
DISPLAY 0.638298 (-2575 2400);
FORCEPROP 1 LAST VOLTAGE 25V
J 0
(-2575 2350);
DISPLAY 0.638298 (-2575 2350);
FORCEPROP 1 LAST TOLERANCE 10%
J 0
(-2575 2300);
DISPLAY 0.638298 (-2575 2300);
FORCEPROP 1 LAST PACK_TYPE 0402
J 0
(-2575 2200);
DISPLAY 0.638298 (-2575 2200);
FORCEPROP 2 LAST ROOM PCIE REDRIVER1_BOM1
J 0
(-2625 2500);
DISPLAY 0.319149 (-2625 2500);
FORCEPROP 1 LAST $LOCATION C1864
J 0
(-2575 2450);
DISPLAY 0.787234 (-2575 2450);
FORCEPROP 1 LASTPIN (-2625 2450) $PN 1
J 0
(-2615 2430);
DISPLAY 0.787234 (-2615 2430);
FORCEPROP 1 LASTPIN (-2625 2250) $PN 2
J 0
(-2615 2230);
DISPLAY 0.787234 (-2615 2230);
FORCEPROP 2 LAST CDS_LIB pure_quanta
J 0
(-2625 2350);
PAINT MONO (-2625 2350);
DISPLAY INVISIBLE (-2625 2350);
FORCEPROP 1 LAST PATH I51
J 0
(-2575 2500);
DISPLAY 0.978723 (-2575 2500);
PAINT WHITE (-2575 2500);
DISPLAY INVISIBLE (-2575 2500);
FORCEPROP 2 LAST CDS_LOCATION C1864
J 0
(-2575 2550);
DISPLAY 1.021277 (-2575 2550);
DISPLAY INVISIBLE (-2575 2550);
FORCEPROP 2 LAST $SEC 1
J 0
(-2575 2550);
DISPLAY 0.680851 (-2575 2550);
PAINT MONO (-2575 2550);
DISPLAY INVISIBLE (-2575 2550);
FORCEPROP 2 LAST CDS_SEC 1
J 0
(-2575 2550);
DISPLAY 1.021277 (-2575 2550);
DISPLAY INVISIBLE (-2575 2550);
FORCEADD Q_CAP..1
(-2350 2350);
FORCEPROP 1 LAST PART_NUMBER CH4104K1B00
J 0
(-2300 2200);
DISPLAY 0.808511 (-2300 2200);
DISPLAY INVISIBLE (-2300 2200);
FORCEPROP 1 LAST PACK_TYPE 0402
J 0
(-2300 2200);
DISPLAY 0.638298 (-2300 2200);
FORCEPROP 1 LAST MATERIAL X7R
J 0
(-2300 2250);
DISPLAY 0.638298 (-2300 2250);
FORCEPROP 1 LAST VOLTAGE 25V
J 0
(-2300 2350);
DISPLAY 0.638298 (-2300 2350);
FORCEPROP 1 LAST TOLERANCE 10%
J 0
(-2300 2300);
DISPLAY 0.638298 (-2300 2300);
FORCEPROP 1 LAST VALUE 0.1UF
J 0
(-2300 2400);
DISPLAY 0.638298 (-2300 2400);
FORCEPROP 2 LAST ROOM PCIE REDRIVER1_BOM1
J 0
(-2350 2525);
DISPLAY 0.510638 (-2350 2525);
FORCEPROP 1 LAST $LOCATION C1865
J 0
(-2300 2450);
DISPLAY 0.787234 (-2300 2450);
FORCEPROP 1 LASTPIN (-2350 2450) $PN 1
J 0
(-2340 2430);
DISPLAY 0.787234 (-2340 2430);
FORCEPROP 1 LASTPIN (-2350 2250) $PN 2
J 0
(-2340 2230);
DISPLAY 0.787234 (-2340 2230);
FORCEPROP 2 LAST CDS_LIB pure_quanta
J 0
(-2350 2350);
PAINT MONO (-2350 2350);
DISPLAY INVISIBLE (-2350 2350);
FORCEPROP 1 LAST PATH I52
J 0
(-2300 2500);
DISPLAY 0.978723 (-2300 2500);
PAINT WHITE (-2300 2500);
DISPLAY INVISIBLE (-2300 2500);
FORCEPROP 2 LAST CDS_LOCATION C1865
J 0
(-2300 2550);
DISPLAY 1.021277 (-2300 2550);
DISPLAY INVISIBLE (-2300 2550);
FORCEPROP 2 LAST $SEC 1
J 0
(-2300 2550);
DISPLAY 0.680851 (-2300 2550);
PAINT MONO (-2300 2550);
DISPLAY INVISIBLE (-2300 2550);
FORCEPROP 2 LAST CDS_SEC 1
J 0
(-2300 2550);
DISPLAY 1.021277 (-2300 2550);
DISPLAY INVISIBLE (-2300 2550);
FORCEADD Q_CAP..1
(-2125 2350);
FORCEPROP 1 LAST PART_NUMBER CH4104K1B00
J 0
(-2075 2200);
DISPLAY 0.808511 (-2075 2200);
DISPLAY INVISIBLE (-2075 2200);
FORCEPROP 1 LAST PACK_TYPE 0402
J 0
(-2075 2200);
DISPLAY 0.638298 (-2075 2200);
FORCEPROP 1 LAST MATERIAL X7R
J 0
(-2075 2250);
DISPLAY 0.638298 (-2075 2250);
FORCEPROP 1 LAST VALUE 0.1UF
J 0
(-2075 2400);
DISPLAY 0.638298 (-2075 2400);
FORCEPROP 1 LAST VOLTAGE 25V
J 0
(-2075 2350);
DISPLAY 0.638298 (-2075 2350);
FORCEPROP 1 LAST TOLERANCE 10%
J 0
(-2075 2300);
DISPLAY 0.638298 (-2075 2300);
FORCEPROP 2 LAST ROOM PCIE REDRIVER1_BOM1
J 0
(-2125 2500);
DISPLAY 0.404255 (-2125 2500);
FORCEPROP 1 LAST $LOCATION C1866
J 0
(-2075 2450);
DISPLAY 0.978723 (-2075 2450);
FORCEPROP 1 LASTPIN (-2125 2450) $PN 1
J 0
(-2115 2430);
DISPLAY 0.787234 (-2115 2430);
PAINT MONO (-2115 2430);
FORCEPROP 1 LASTPIN (-2125 2250) $PN 2
J 0
(-2115 2230);
DISPLAY 0.787234 (-2115 2230);
PAINT MONO (-2115 2230);
FORCEPROP 2 LAST CDS_LIB pure_quanta
J 0
(-2125 2350);
DISPLAY INVISIBLE (-2125 2350);
FORCEPROP 1 LAST PATH I53
J 0
(-2075 2500);
DISPLAY 0.978723 (-2075 2500);
PAINT WHITE (-2075 2500);
DISPLAY INVISIBLE (-2075 2500);
FORCEPROP 0 LAST CDS_LOCATION C1866
J 0
(-2075 2500);
DISPLAY 1.021277 (-2075 2500);
DISPLAY INVISIBLE (-2075 2500);
FORCEPROP 0 LAST $SEC 1
J 0
(-2075 2500);
DISPLAY 0.680851 (-2075 2500);
PAINT MONO (-2075 2500);
DISPLAY INVISIBLE (-2075 2500);
FORCEPROP 0 LAST CDS_SEC 1
J 0
(-2075 2500);
DISPLAY 1.021277 (-2075 2500);
DISPLAY INVISIBLE (-2075 2500);
FORCEADD UNIVERSAL_POWER..1
(-1875 2750);
FORCEPROP 3 LASTPIN (-1875 2700) SIG_NAME P3V3_AUX\g
J 0
(-1865 2710);
DISPLAY 0.659574 (-1865 2710);
PAINT MONO (-1865 2710);
DISPLAY INVISIBLE (-1865 2710);
FORCEPROP 1 LAST HDL_POWER P3V3_AUX
J 1
(-1875 2800);
DISPLAY 0.872340 (-1875 2800);
PAINT GREEN (-1875 2800);
FORCEPROP 2 LAST CDS_LIB logical_power
J 0
(-1875 2750);
DISPLAY INVISIBLE (-1875 2750);
FORCEPROP 1 LAST PATH I54
J 0
(-1825 2775);
DISPLAY 0.872340 (-1825 2775);
PAINT AQUA (-1825 2775);
DISPLAY INVISIBLE (-1825 2775);
FORCEADD UNIVERSAL_GND..1
(-825 -2900);
FORCEPROP 3 LASTPIN (-825 -2850) SIG_NAME GND\g
J 0
(-815 -2840);
DISPLAY 0.659574 (-815 -2840);
PAINT MONO (-815 -2840);
DISPLAY INVISIBLE (-815 -2840);
FORCEPROP 2 LAST ROOM IO_SLOT
J 1
(-1050 -2825);
DISPLAY 0.744681 (-1050 -2825);
DISPLAY INVISIBLE (-1050 -2825);
FORCEPROP 2 LAST CDS_LIB logical_power
J 0
(-825 -2900);
DISPLAY INVISIBLE (-825 -2900);
FORCEPROP 1 LAST HDL_POWER GND
J 1
(-800 -2975);
DISPLAY 0.872340 (-800 -2975);
PAINT GREEN (-800 -2975);
DISPLAY INVISIBLE (-800 -2975);
FORCEPROP 1 LAST PATH I55
J 0
(-750 -2900);
DISPLAY 0.872340 (-750 -2900);
PAINT AQUA (-750 -2900);
DISPLAY INVISIBLE (-750 -2900);
FORCEADD Q_RES..2
(-825 -2600);
FORCEPROP 1 LAST PART_NUMBER CS21002FB06
J 0
(-785 -2725);
DISPLAY 0.638298 (-785 -2725);
DISPLAY INVISIBLE (-785 -2725);
FORCEPROP 1 LAST PACK_TYPE 0402LF
J 0
(-785 -2775);
DISPLAY 0.638298 (-785 -2775);
FORCEPROP 1 LAST VALUE 1K
J 0
(-780 -2525);
DISPLAY 0.638298 (-780 -2525);
FORCEPROP 1 LAST TOLERANCE 1%
J 0
(-780 -2575);
DISPLAY 0.638298 (-780 -2575);
FORCEPROP 1 LAST WATTAGE 1/16W
J 0
(-785 -2625);
DISPLAY 0.638298 (-785 -2625);
FORCEPROP 1 LAST MATERIAL CHIP
J 0
(-785 -2675);
DISPLAY 0.638298 (-785 -2675);
FORCEPROP 2 LAST ROOM PCIE REDRIVER1_BOM1
J 0
(-775 -2425);
DISPLAY 0.808511 (-775 -2425);
FORCEPROP 1 LAST $LOCATION R3284
J 0
(-780 -2475);
DISPLAY 0.978723 (-780 -2475);
FORCEPROP 1 LASTPIN (-825 -2500) $PN 1
J 0
(-820 -2538);
DISPLAY 0.787234 (-820 -2538);
PAINT MONO (-820 -2538);
FORCEPROP 1 LASTPIN (-825 -2700) $PN 2
J 0
(-820 -2690);
DISPLAY 0.787234 (-820 -2690);
PAINT MONO (-820 -2690);
FORCEPROP 2 LAST CDS_LIB pure_quanta
J 0
(-825 -2600);
DISPLAY INVISIBLE (-825 -2600);
FORCEPROP 1 LAST PATH I56
J 0
(-775 -2425);
DISPLAY 0.978723 (-775 -2425);
PAINT WHITE (-775 -2425);
DISPLAY INVISIBLE (-775 -2425);
FORCEPROP 0 LAST CDS_LOCATION R3284
J 0
(-775 -2425);
DISPLAY 1.021277 (-775 -2425);
DISPLAY INVISIBLE (-775 -2425);
FORCEPROP 0 LAST $SEC 1
J 0
(-775 -2425);
DISPLAY 0.680851 (-775 -2425);
PAINT MONO (-775 -2425);
DISPLAY INVISIBLE (-775 -2425);
FORCEPROP 0 LAST CDS_SEC 1
J 0
(-775 -2425);
DISPLAY 1.021277 (-775 -2425);
DISPLAY INVISIBLE (-775 -2425);
FORCEADD Q_RES..2
(-825 -2025);
FORCEPROP 1 LAST PART_NUMBER CS21002FB06
J 0
(-785 -2150);
DISPLAY 0.638298 (-785 -2150);
DISPLAY INVISIBLE (-785 -2150);
FORCEPROP 1 LAST WATTAGE 1/16W
J 0
(-785 -2050);
DISPLAY 0.638298 (-785 -2050);
FORCEPROP 1 LAST MATERIAL EMPTY
J 0
(-785 -2100);
DISPLAY 0.638298 (-785 -2100);
PAINT RED (-785 -2100);
FORCEPROP 1 LAST TOLERANCE 1%
J 0
(-780 -2000);
DISPLAY 0.638298 (-780 -2000);
FORCEPROP 1 LAST VALUE 1K
J 0
(-780 -1950);
DISPLAY 0.638298 (-780 -1950);
FORCEPROP 1 LAST PACK_TYPE 0402LF
J 0
(-785 -2200);
DISPLAY 0.638298 (-785 -2200);
FORCEPROP 1 LAST $LOCATION R3283
J 0
(-780 -1900);
DISPLAY 0.978723 (-780 -1900);
FORCEPROP 1 LASTPIN (-825 -1925) $PN 1
J 0
(-820 -1963);
DISPLAY 0.787234 (-820 -1963);
PAINT MONO (-820 -1963);
FORCEPROP 1 LASTPIN (-825 -2125) $PN 2
J 0
(-820 -2115);
DISPLAY 0.787234 (-820 -2115);
PAINT MONO (-820 -2115);
FORCEPROP 2 LAST CDS_LIB pure_quanta
J 0
(-825 -2025);
DISPLAY INVISIBLE (-825 -2025);
FORCEPROP 1 LAST PATH I57
J 0
(-775 -1850);
DISPLAY 0.978723 (-775 -1850);
PAINT WHITE (-775 -1850);
DISPLAY INVISIBLE (-775 -1850);
FORCEPROP 0 LAST CDS_LOCATION R3283
J 0
(-775 -1850);
DISPLAY 1.021277 (-775 -1850);
DISPLAY INVISIBLE (-775 -1850);
FORCEPROP 0 LAST $SEC 1
J 0
(-775 -1850);
DISPLAY 0.680851 (-775 -1850);
PAINT MONO (-775 -1850);
DISPLAY INVISIBLE (-775 -1850);
FORCEPROP 0 LAST CDS_SEC 1
J 0
(-775 -1850);
DISPLAY 1.021277 (-775 -1850);
DISPLAY INVISIBLE (-775 -1850);
FORCEADD OFFPAGE..2
(-325 -2275);
FORCEPROP 2 LAST $XR0 166 
J 0
(-136 -2275);
DISPLAY 0.638298 (-136 -2275);
PAINT MONO (-136 -2275);
FORCEPROP 2 LAST CDS_LIB standard
J 0
(-325 -2275);
DISPLAY INVISIBLE (-325 -2275);
FORCEPROP 1 LAST OFFPAGE TRUE
J 0
(0 -2400);
DISPLAY 0.872340 (0 -2400);
PAINT GREEN (0 -2400);
DISPLAY INVISIBLE (0 -2400);
FORCEPROP 1 LAST COMMENT_BODY TRUE
J 0
(-370 -2370);
DISPLAY 0.872340 (-370 -2370);
PAINT GREEN (-370 -2370);
DISPLAY INVISIBLE (-370 -2370);
FORCEPROP 2 LAST PATH I58
J 0
(-125 -2225);
DISPLAY 1.021277 (-125 -2225);
DISPLAY INVISIBLE (-125 -2225);
FORCEADD OFFPAGE..2
(-325 -2325);
FORCEPROP 2 LAST $XR0 166 
J 0
(-136 -2325);
DISPLAY 0.638298 (-136 -2325);
PAINT MONO (-136 -2325);
FORCEPROP 2 LAST CDS_LIB standard
J 0
(-325 -2325);
DISPLAY INVISIBLE (-325 -2325);
FORCEPROP 1 LAST OFFPAGE TRUE
J 0
(0 -2450);
DISPLAY 0.872340 (0 -2450);
PAINT GREEN (0 -2450);
DISPLAY INVISIBLE (0 -2450);
FORCEPROP 1 LAST COMMENT_BODY TRUE
J 0
(-370 -2420);
DISPLAY 0.872340 (-370 -2420);
PAINT GREEN (-370 -2420);
DISPLAY INVISIBLE (-370 -2420);
FORCEPROP 2 LAST PATH I59
J 0
(-125 -2275);
DISPLAY 1.021277 (-125 -2275);
DISPLAY INVISIBLE (-125 -2275);
FORCEADD Q_RES..2
(-3475 -2550);
FORCEPROP 1 LAST PART_NUMBER CS36802FB04
J 0
(-3435 -2675);
DISPLAY 0.638298 (-3435 -2675);
DISPLAY INVISIBLE (-3435 -2675);
FORCEPROP 1 LAST MATERIAL EMPTY
J 0
(-3435 -2625);
DISPLAY 0.638298 (-3435 -2625);
PAINT RED (-3435 -2625);
FORCEPROP 1 LAST PACK_TYPE 0402LF
J 0
(-3435 -2725);
DISPLAY 0.638298 (-3435 -2725);
FORCEPROP 1 LAST VALUE 68K
J 0
(-3430 -2475);
DISPLAY 0.638298 (-3430 -2475);
FORCEPROP 1 LAST WATTAGE 1/16W
J 0
(-3435 -2575);
DISPLAY 0.638298 (-3435 -2575);
FORCEPROP 1 LAST TOLERANCE 1%
J 0
(-3430 -2525);
DISPLAY 0.638298 (-3430 -2525);
FORCEPROP 1 LAST $LOCATION R3274
J 0
(-3430 -2425);
DISPLAY 0.978723 (-3430 -2425);
FORCEPROP 1 LASTPIN (-3475 -2450) $PN 1
J 0
(-3470 -2488);
DISPLAY 0.787234 (-3470 -2488);
PAINT MONO (-3470 -2488);
FORCEPROP 1 LASTPIN (-3475 -2650) $PN 2
J 0
(-3470 -2640);
DISPLAY 0.787234 (-3470 -2640);
PAINT MONO (-3470 -2640);
FORCEPROP 2 LAST CDS_LIB pure_quanta
J 0
(-3475 -2550);
DISPLAY INVISIBLE (-3475 -2550);
FORCEPROP 1 LAST PATH I6
J 0
(-3425 -2375);
DISPLAY 0.978723 (-3425 -2375);
PAINT WHITE (-3425 -2375);
DISPLAY INVISIBLE (-3425 -2375);
FORCEPROP 0 LAST CDS_LOCATION R3274
J 0
(-3425 -2375);
DISPLAY 1.021277 (-3425 -2375);
DISPLAY INVISIBLE (-3425 -2375);
FORCEPROP 0 LAST $SEC 1
J 0
(-3425 -2375);
DISPLAY 0.680851 (-3425 -2375);
PAINT MONO (-3425 -2375);
DISPLAY INVISIBLE (-3425 -2375);
FORCEPROP 0 LAST CDS_SEC 1
J 0
(-3425 -2375);
DISPLAY 1.021277 (-3425 -2375);
DISPLAY INVISIBLE (-3425 -2375);
FORCEADD UNIVERSAL_GND..1
(-50 -1150);
FORCEPROP 3 LASTPIN (-50 -1100) SIG_NAME GND\g
J 0
(-40 -1090);
DISPLAY 0.659574 (-40 -1090);
PAINT MONO (-40 -1090);
DISPLAY INVISIBLE (-40 -1090);
FORCEPROP 2 LAST ROOM IO_SLOT
J 1
(-275 -1075);
DISPLAY 0.744681 (-275 -1075);
DISPLAY INVISIBLE (-275 -1075);
FORCEPROP 2 LAST CDS_LIB logical_power
J 0
(-50 -1150);
DISPLAY INVISIBLE (-50 -1150);
FORCEPROP 1 LAST HDL_POWER GND
J 1
(-25 -1225);
DISPLAY 0.872340 (-25 -1225);
PAINT GREEN (-25 -1225);
DISPLAY INVISIBLE (-25 -1225);
FORCEPROP 1 LAST PATH I60
J 0
(25 -1150);
DISPLAY 0.872340 (25 -1150);
PAINT AQUA (25 -1150);
DISPLAY INVISIBLE (25 -1150);
FORCEADD Q_RES..2
(-50 -800);
FORCEPROP 1 LAST PART_NUMBER CS36802FB04
J 0
(-10 -925);
DISPLAY 0.638298 (-10 -925);
DISPLAY INVISIBLE (-10 -925);
FORCEPROP 1 LAST TOLERANCE 1%
J 0
(-5 -775);
DISPLAY 0.638298 (-5 -775);
FORCEPROP 1 LAST WATTAGE 1/16W
J 0
(-10 -825);
DISPLAY 0.638298 (-10 -825);
FORCEPROP 1 LAST MATERIAL EMPTY
J 0
(-10 -875);
DISPLAY 0.638298 (-10 -875);
PAINT RED (-10 -875);
FORCEPROP 1 LAST VALUE 68K
J 0
(-5 -725);
DISPLAY 0.638298 (-5 -725);
FORCEPROP 1 LAST PACK_TYPE 0402LF
J 0
(-10 -975);
DISPLAY 0.638298 (-10 -975);
FORCEPROP 1 LAST $LOCATION R3285
J 0
(-5 -675);
DISPLAY 0.638298 (-5 -675);
FORCEPROP 1 LASTPIN (-50 -700) $PN 1
J 0
(-45 -738);
DISPLAY 0.787234 (-45 -738);
PAINT MONO (-45 -738);
FORCEPROP 1 LASTPIN (-50 -900) $PN 2
J 0
(-45 -890);
DISPLAY 0.787234 (-45 -890);
PAINT MONO (-45 -890);
FORCEPROP 2 LAST CDS_LIB pure_quanta
J 0
(-50 -800);
DISPLAY INVISIBLE (-50 -800);
FORCEPROP 1 LAST PATH I61
J 0
(0 -625);
DISPLAY 0.978723 (0 -625);
PAINT WHITE (0 -625);
DISPLAY INVISIBLE (0 -625);
FORCEPROP 0 LAST CDS_LOCATION R3285
J 0
(0 -625);
DISPLAY 1.021277 (0 -625);
DISPLAY INVISIBLE (0 -625);
FORCEPROP 0 LAST $SEC 1
J 0
(0 -625);
DISPLAY 0.680851 (0 -625);
PAINT MONO (0 -625);
DISPLAY INVISIBLE (0 -625);
FORCEPROP 0 LAST CDS_SEC 1
J 0
(0 -625);
DISPLAY 1.021277 (0 -625);
DISPLAY INVISIBLE (0 -625);
FORCEADD UNIVERSAL_GND..1
(325 -1150);
FORCEPROP 3 LASTPIN (325 -1100) SIG_NAME GND\g
J 0
(335 -1090);
DISPLAY 0.659574 (335 -1090);
PAINT MONO (335 -1090);
DISPLAY INVISIBLE (335 -1090);
FORCEPROP 2 LAST ROOM IO_SLOT
J 1
(100 -1075);
DISPLAY 0.744681 (100 -1075);
DISPLAY INVISIBLE (100 -1075);
FORCEPROP 2 LAST CDS_LIB logical_power
J 0
(325 -1150);
DISPLAY INVISIBLE (325 -1150);
FORCEPROP 1 LAST HDL_POWER GND
J 1
(350 -1225);
DISPLAY 0.872340 (350 -1225);
PAINT GREEN (350 -1225);
DISPLAY INVISIBLE (350 -1225);
FORCEPROP 1 LAST PATH I62
J 0
(400 -1150);
DISPLAY 0.872340 (400 -1150);
PAINT AQUA (400 -1150);
DISPLAY INVISIBLE (400 -1150);
FORCEADD Q_RES..2
(325 -800);
FORCEPROP 1 LAST PART_NUMBER CS21002FB06
J 0
(365 -925);
DISPLAY 0.638298 (365 -925);
DISPLAY INVISIBLE (365 -925);
FORCEPROP 1 LAST VALUE 1K
J 0
(370 -725);
DISPLAY 0.638298 (370 -725);
FORCEPROP 1 LAST TOLERANCE 1%
J 0
(370 -775);
DISPLAY 0.638298 (370 -775);
FORCEPROP 1 LAST WATTAGE 1/16W
J 0
(365 -825);
DISPLAY 0.638298 (365 -825);
FORCEPROP 1 LAST MATERIAL EMPTY
J 0
(365 -875);
DISPLAY 0.638298 (365 -875);
PAINT RED (365 -875);
FORCEPROP 1 LAST PACK_TYPE 0402LF
J 0
(365 -975);
DISPLAY 0.638298 (365 -975);
FORCEPROP 1 LAST $LOCATION R3287
J 0
(370 -675);
DISPLAY 0.978723 (370 -675);
FORCEPROP 1 LASTPIN (325 -700) $PN 1
J 0
(330 -738);
DISPLAY 0.787234 (330 -738);
PAINT MONO (330 -738);
FORCEPROP 1 LASTPIN (325 -900) $PN 2
J 0
(330 -890);
DISPLAY 0.787234 (330 -890);
PAINT MONO (330 -890);
FORCEPROP 2 LAST CDS_LIB pure_quanta
J 0
(325 -800);
DISPLAY INVISIBLE (325 -800);
FORCEPROP 1 LAST PATH I63
J 0
(375 -625);
DISPLAY 0.978723 (375 -625);
PAINT WHITE (375 -625);
DISPLAY INVISIBLE (375 -625);
FORCEPROP 0 LAST CDS_LOCATION R3287
J 0
(375 -625);
DISPLAY 1.021277 (375 -625);
DISPLAY INVISIBLE (375 -625);
FORCEPROP 0 LAST $SEC 1
J 0
(375 -625);
DISPLAY 0.680851 (375 -625);
PAINT MONO (375 -625);
DISPLAY INVISIBLE (375 -625);
FORCEPROP 0 LAST CDS_SEC 1
J 0
(375 -625);
DISPLAY 1.021277 (375 -625);
DISPLAY INVISIBLE (375 -625);
FORCEADD Q_RES..2
(325 -275);
FORCEPROP 1 LAST PART_NUMBER CS21002FB06
J 0
(365 -400);
DISPLAY 0.638298 (365 -400);
DISPLAY INVISIBLE (365 -400);
FORCEPROP 1 LAST VALUE 1K
J 0
(370 -200);
DISPLAY 0.638298 (370 -200);
FORCEPROP 1 LAST PACK_TYPE 0402LF
J 0
(365 -450);
DISPLAY 0.638298 (365 -450);
FORCEPROP 1 LAST TOLERANCE 1%
J 0
(370 -250);
DISPLAY 0.638298 (370 -250);
FORCEPROP 1 LAST WATTAGE 1/16W
J 0
(365 -300);
DISPLAY 0.638298 (365 -300);
FORCEPROP 1 LAST MATERIAL EMPTY
J 0
(365 -350);
DISPLAY 0.638298 (365 -350);
PAINT RED (365 -350);
FORCEPROP 1 LAST $LOCATION R3286
J 0
(370 -150);
DISPLAY 0.638298 (370 -150);
FORCEPROP 1 LASTPIN (325 -175) $PN 1
J 0
(330 -213);
DISPLAY 0.787234 (330 -213);
PAINT MONO (330 -213);
FORCEPROP 1 LASTPIN (325 -375) $PN 2
J 0
(330 -365);
DISPLAY 0.787234 (330 -365);
PAINT MONO (330 -365);
FORCEPROP 2 LAST CDS_LIB pure_quanta
J 0
(325 -275);
DISPLAY INVISIBLE (325 -275);
FORCEPROP 1 LAST PATH I64
J 0
(375 -100);
DISPLAY 0.978723 (375 -100);
PAINT WHITE (375 -100);
DISPLAY INVISIBLE (375 -100);
FORCEPROP 0 LAST CDS_LOCATION R3286
J 0
(375 -100);
DISPLAY 1.021277 (375 -100);
DISPLAY INVISIBLE (375 -100);
FORCEPROP 0 LAST $SEC 1
J 0
(375 -100);
DISPLAY 0.680851 (375 -100);
PAINT MONO (375 -100);
DISPLAY INVISIBLE (375 -100);
FORCEPROP 0 LAST CDS_SEC 1
J 0
(375 -100);
DISPLAY 1.021277 (375 -100);
DISPLAY INVISIBLE (375 -100);
FORCEADD UNIVERSAL_GND..1
(800 -1150);
FORCEPROP 3 LASTPIN (800 -1100) SIG_NAME GND\g
J 0
(810 -1090);
DISPLAY 0.659574 (810 -1090);
PAINT MONO (810 -1090);
DISPLAY INVISIBLE (810 -1090);
FORCEPROP 2 LAST ROOM IO_SLOT
J 1
(575 -1075);
DISPLAY 0.744681 (575 -1075);
DISPLAY INVISIBLE (575 -1075);
FORCEPROP 2 LAST CDS_LIB logical_power
J 0
(800 -1150);
DISPLAY INVISIBLE (800 -1150);
FORCEPROP 1 LAST HDL_POWER GND
J 1
(825 -1225);
DISPLAY 0.872340 (825 -1225);
PAINT GREEN (825 -1225);
DISPLAY INVISIBLE (825 -1225);
FORCEPROP 1 LAST PATH I65
J 0
(875 -1150);
DISPLAY 0.872340 (875 -1150);
PAINT AQUA (875 -1150);
DISPLAY INVISIBLE (875 -1150);
FORCEADD Q_RES..2
(800 -825);
FORCEPROP 1 LAST PART_NUMBER CS36802FB04
J 0
(840 -950);
DISPLAY 0.638298 (840 -950);
DISPLAY INVISIBLE (840 -950);
FORCEPROP 1 LAST WATTAGE 1/16W
J 0
(840 -850);
DISPLAY 0.638298 (840 -850);
FORCEPROP 1 LAST TOLERANCE 1%
J 0
(845 -800);
DISPLAY 0.638298 (845 -800);
FORCEPROP 1 LAST PACK_TYPE 0402LF
J 0
(840 -1000);
DISPLAY 0.638298 (840 -1000);
FORCEPROP 1 LAST MATERIAL EMPTY
J 0
(840 -900);
DISPLAY 0.638298 (840 -900);
PAINT RED (840 -900);
FORCEPROP 1 LAST VALUE 68K
J 0
(845 -750);
DISPLAY 0.638298 (845 -750);
FORCEPROP 1 LAST $LOCATION R3288
J 0
(845 -700);
DISPLAY 0.978723 (845 -700);
FORCEPROP 1 LASTPIN (800 -725) $PN 1
J 0
(805 -763);
DISPLAY 0.787234 (805 -763);
PAINT MONO (805 -763);
FORCEPROP 1 LASTPIN (800 -925) $PN 2
J 0
(805 -915);
DISPLAY 0.787234 (805 -915);
PAINT MONO (805 -915);
FORCEPROP 2 LAST CDS_LIB pure_quanta
J 0
(800 -825);
DISPLAY INVISIBLE (800 -825);
FORCEPROP 1 LAST PATH I66
J 0
(850 -650);
DISPLAY 0.978723 (850 -650);
PAINT WHITE (850 -650);
DISPLAY INVISIBLE (850 -650);
FORCEPROP 0 LAST CDS_LOCATION R3288
J 0
(850 -650);
DISPLAY 1.021277 (850 -650);
DISPLAY INVISIBLE (850 -650);
FORCEPROP 0 LAST $SEC 1
J 0
(850 -650);
DISPLAY 0.680851 (850 -650);
PAINT MONO (850 -650);
DISPLAY INVISIBLE (850 -650);
FORCEPROP 0 LAST CDS_SEC 1
J 0
(850 -650);
DISPLAY 1.021277 (850 -650);
DISPLAY INVISIBLE (850 -650);
FORCEADD UNIVERSAL_GND..1
(1200 -1150);
FORCEPROP 3 LASTPIN (1200 -1100) SIG_NAME GND\g
J 0
(1210 -1090);
DISPLAY 0.659574 (1210 -1090);
PAINT MONO (1210 -1090);
DISPLAY INVISIBLE (1210 -1090);
FORCEPROP 2 LAST ROOM IO_SLOT
J 1
(975 -1075);
DISPLAY 0.744681 (975 -1075);
DISPLAY INVISIBLE (975 -1075);
FORCEPROP 2 LAST CDS_LIB logical_power
J 0
(1200 -1150);
DISPLAY INVISIBLE (1200 -1150);
FORCEPROP 1 LAST HDL_POWER GND
J 1
(1225 -1225);
DISPLAY 0.872340 (1225 -1225);
PAINT GREEN (1225 -1225);
DISPLAY INVISIBLE (1225 -1225);
FORCEPROP 1 LAST PATH I67
J 0
(1275 -1150);
DISPLAY 0.872340 (1275 -1150);
PAINT AQUA (1275 -1150);
DISPLAY INVISIBLE (1275 -1150);
FORCEADD Q_RES..2
(1200 -850);
FORCEPROP 1 LAST PART_NUMBER CS21002FB06
J 0
(1240 -975);
DISPLAY 0.638298 (1240 -975);
DISPLAY INVISIBLE (1240 -975);
FORCEPROP 1 LAST PACK_TYPE 0402LF
J 0
(1240 -1025);
DISPLAY 0.638298 (1240 -1025);
FORCEPROP 1 LAST MATERIAL EMPTY
J 0
(1240 -925);
DISPLAY 0.638298 (1240 -925);
PAINT RED (1240 -925);
FORCEPROP 1 LAST WATTAGE 1/16W
J 0
(1240 -875);
DISPLAY 0.638298 (1240 -875);
FORCEPROP 1 LAST TOLERANCE 1%
J 0
(1245 -825);
DISPLAY 0.638298 (1245 -825);
FORCEPROP 1 LAST VALUE 1K
J 0
(1245 -775);
DISPLAY 0.638298 (1245 -775);
FORCEPROP 1 LAST $LOCATION R3290
J 0
(1245 -725);
DISPLAY 0.978723 (1245 -725);
FORCEPROP 1 LASTPIN (1200 -750) $PN 1
J 0
(1205 -788);
DISPLAY 0.787234 (1205 -788);
PAINT MONO (1205 -788);
FORCEPROP 1 LASTPIN (1200 -950) $PN 2
J 0
(1205 -940);
DISPLAY 0.787234 (1205 -940);
PAINT MONO (1205 -940);
FORCEPROP 2 LAST CDS_LIB pure_quanta
J 0
(1200 -850);
DISPLAY INVISIBLE (1200 -850);
FORCEPROP 1 LAST PATH I68
J 0
(1250 -675);
DISPLAY 0.978723 (1250 -675);
PAINT WHITE (1250 -675);
DISPLAY INVISIBLE (1250 -675);
FORCEPROP 0 LAST CDS_LOCATION R3290
J 0
(1250 -675);
DISPLAY 1.021277 (1250 -675);
DISPLAY INVISIBLE (1250 -675);
FORCEPROP 0 LAST $SEC 1
J 0
(1250 -675);
DISPLAY 0.680851 (1250 -675);
PAINT MONO (1250 -675);
DISPLAY INVISIBLE (1250 -675);
FORCEPROP 0 LAST CDS_SEC 1
J 0
(1250 -675);
DISPLAY 1.021277 (1250 -675);
DISPLAY INVISIBLE (1250 -675);
FORCEADD Q_RES..2
(1200 -275);
FORCEPROP 1 LAST PART_NUMBER CS21002FB06
J 0
(1240 -400);
DISPLAY 0.638298 (1240 -400);
DISPLAY INVISIBLE (1240 -400);
FORCEPROP 1 LAST WATTAGE 1/16W
J 0
(1240 -300);
DISPLAY 0.638298 (1240 -300);
FORCEPROP 1 LAST VALUE 1K
J 0
(1245 -200);
DISPLAY 0.638298 (1245 -200);
FORCEPROP 1 LAST TOLERANCE 1%
J 0
(1245 -250);
DISPLAY 0.638298 (1245 -250);
FORCEPROP 1 LAST MATERIAL EMPTY
J 0
(1240 -350);
DISPLAY 0.638298 (1240 -350);
PAINT RED (1240 -350);
FORCEPROP 1 LAST PACK_TYPE 0402LF
J 0
(1240 -450);
DISPLAY 0.638298 (1240 -450);
FORCEPROP 1 LAST $LOCATION R3289
J 0
(1245 -150);
DISPLAY 0.978723 (1245 -150);
FORCEPROP 1 LASTPIN (1200 -175) $PN 1
J 0
(1205 -213);
DISPLAY 0.787234 (1205 -213);
PAINT MONO (1205 -213);
FORCEPROP 1 LASTPIN (1200 -375) $PN 2
J 0
(1205 -365);
DISPLAY 0.787234 (1205 -365);
PAINT MONO (1205 -365);
FORCEPROP 2 LAST CDS_LIB pure_quanta
J 0
(1200 -275);
DISPLAY INVISIBLE (1200 -275);
FORCEPROP 1 LAST PATH I69
J 0
(1250 -100);
DISPLAY 0.978723 (1250 -100);
PAINT WHITE (1250 -100);
DISPLAY INVISIBLE (1250 -100);
FORCEPROP 0 LAST CDS_LOCATION R3289
J 0
(1250 -100);
DISPLAY 1.021277 (1250 -100);
DISPLAY INVISIBLE (1250 -100);
FORCEPROP 0 LAST $SEC 1
J 0
(1250 -100);
DISPLAY 0.680851 (1250 -100);
PAINT MONO (1250 -100);
DISPLAY INVISIBLE (1250 -100);
FORCEPROP 0 LAST CDS_SEC 1
J 0
(1250 -100);
DISPLAY 1.021277 (1250 -100);
DISPLAY INVISIBLE (1250 -100);
FORCEADD UNIVERSAL_GND..1
(-3075 -2875);
FORCEPROP 3 LASTPIN (-3075 -2825) SIG_NAME GND\g
J 0
(-3065 -2815);
DISPLAY 0.659574 (-3065 -2815);
PAINT MONO (-3065 -2815);
DISPLAY INVISIBLE (-3065 -2815);
FORCEPROP 2 LAST ROOM IO_SLOT
J 1
(-3300 -2800);
DISPLAY 0.744681 (-3300 -2800);
DISPLAY INVISIBLE (-3300 -2800);
FORCEPROP 2 LAST CDS_LIB logical_power
J 0
(-3075 -2875);
DISPLAY INVISIBLE (-3075 -2875);
FORCEPROP 1 LAST HDL_POWER GND
J 1
(-3050 -2950);
DISPLAY 0.872340 (-3050 -2950);
PAINT GREEN (-3050 -2950);
DISPLAY INVISIBLE (-3050 -2950);
FORCEPROP 1 LAST PATH I7
J 0
(-3000 -2875);
DISPLAY 0.872340 (-3000 -2875);
PAINT AQUA (-3000 -2875);
DISPLAY INVISIBLE (-3000 -2875);
FORCEADD OFFPAGE..2
(1675 -575);
FORCEPROP 2 LAST $XR0 166 
J 0
(1864 -575);
DISPLAY 0.638298 (1864 -575);
PAINT MONO (1864 -575);
FORCEPROP 2 LAST CDS_LIB standard
J 0
(1675 -575);
DISPLAY INVISIBLE (1675 -575);
FORCEPROP 1 LAST OFFPAGE TRUE
J 0
(2000 -700);
DISPLAY 0.872340 (2000 -700);
PAINT GREEN (2000 -700);
DISPLAY INVISIBLE (2000 -700);
FORCEPROP 1 LAST COMMENT_BODY TRUE
J 0
(1630 -670);
DISPLAY 0.872340 (1630 -670);
PAINT GREEN (1630 -670);
DISPLAY INVISIBLE (1630 -670);
FORCEPROP 2 LAST PATH I70
J 0
(1875 -525);
DISPLAY 1.021277 (1875 -525);
DISPLAY INVISIBLE (1875 -525);
FORCEADD OFFPAGE..2
(1675 -525);
FORCEPROP 2 LAST $XR0 166 
J 0
(1864 -525);
DISPLAY 0.638298 (1864 -525);
PAINT MONO (1864 -525);
FORCEPROP 2 LAST CDS_LIB standard
J 0
(1675 -525);
DISPLAY INVISIBLE (1675 -525);
FORCEPROP 1 LAST OFFPAGE TRUE
J 0
(2000 -650);
DISPLAY 0.872340 (2000 -650);
PAINT GREEN (2000 -650);
DISPLAY INVISIBLE (2000 -650);
FORCEPROP 1 LAST COMMENT_BODY TRUE
J 0
(1630 -620);
DISPLAY 0.872340 (1630 -620);
PAINT GREEN (1630 -620);
DISPLAY INVISIBLE (1630 -620);
FORCEPROP 2 LAST PATH I71
J 0
(1875 -475);
DISPLAY 1.021277 (1875 -475);
DISPLAY INVISIBLE (1875 -475);
FORCEADD UNIVERSAL_GND..1
(-775 625);
FORCEPROP 3 LASTPIN (-775 675) SIG_NAME GND\g
J 0
(-765 685);
DISPLAY 0.659574 (-765 685);
PAINT MONO (-765 685);
DISPLAY INVISIBLE (-765 685);
FORCEPROP 2 LAST CDS_LIB logical_power
J 0
(-775 625);
DISPLAY INVISIBLE (-775 625);
FORCEPROP 1 LAST HDL_POWER GND
J 1
(-750 550);
DISPLAY 0.872340 (-750 550);
PAINT GREEN (-750 550);
DISPLAY INVISIBLE (-750 550);
FORCEPROP 1 LAST PATH I72
J 0
(-700 625);
DISPLAY 0.872340 (-700 625);
PAINT AQUA (-700 625);
DISPLAY INVISIBLE (-700 625);
FORCEADD Q_RES..1
(-250 1500);
FORCEPROP 1 LAST PART_NUMBER CS00002JB13
J 0
(-525 1375);
DISPLAY 0.723404 (-525 1375);
PAINT WHITE (-525 1375);
DISPLAY INVISIBLE (-525 1375);
FORCEPROP 1 LAST VALUE 0
J 2
(-100 1500);
DISPLAY 0.574468 (-100 1500);
FORCEPROP 1 LAST PACK_TYPE 0402LF
J 0
(50 1500);
DISPLAY 0.574468 (50 1500);
FORCEPROP 1 LAST MATERIAL CHIP
J 0
(-75 1500);
DISPLAY 0.574468 (-75 1500);
FORCEPROP 2 LAST ROOM PCIE REDRIVER1_BOM1
J 0
(-550 1425);
DISPLAY 1.021277 (-550 1425);
FORCEPROP 1 LAST $LOCATION R4537
J 0
(-300 1550);
DISPLAY 0.978723 (-300 1550);
FORCEPROP 1 LASTPIN (-350 1500) $PN 1
J 0
(-338 1512);
DISPLAY 0.787234 (-338 1512);
PAINT MONO (-338 1512);
FORCEPROP 1 LASTPIN (-150 1500) $PN 2
J 0
(-188 1512);
DISPLAY 0.787234 (-188 1512);
PAINT MONO (-188 1512);
FORCEPROP 1 LAST WATTAGE 1/16W
J 2
(-175 1425);
DISPLAY 0.723404 (-175 1425);
PAINT SKYBLUE (-175 1425);
DISPLAY INVISIBLE (-175 1425);
FORCEPROP 1 LAST TOLERANCE 5%
J 0
(-450 1425);
DISPLAY 0.723404 (-450 1425);
PAINT SKYBLUE (-450 1425);
DISPLAY INVISIBLE (-450 1425);
FORCEPROP 2 LAST CDS_LIB pure_quanta
J 0
(-250 1500);
DISPLAY INVISIBLE (-250 1500);
FORCEPROP 1 LAST PATH I73
J 0
(-300 1650);
DISPLAY 0.978723 (-300 1650);
PAINT WHITE (-300 1650);
DISPLAY INVISIBLE (-300 1650);
FORCEPROP 0 LAST CDS_LOCATION R4537
J 0
(-300 1600);
DISPLAY 1.021277 (-300 1600);
DISPLAY INVISIBLE (-300 1600);
FORCEPROP 0 LAST $SEC 1
J 0
(-300 1600);
DISPLAY 0.680851 (-300 1600);
PAINT MONO (-300 1600);
DISPLAY INVISIBLE (-300 1600);
FORCEPROP 0 LAST CDS_SEC 1
J 0
(-300 1600);
DISPLAY 1.021277 (-300 1600);
DISPLAY INVISIBLE (-300 1600);
FORCEADD UNIVERSAL_POWER..1
(325 25);
FORCEPROP 3 LASTPIN (325 -25) SIG_NAME P3V3_AUX\g
J 0
(335 -15);
DISPLAY 0.659574 (335 -15);
PAINT MONO (335 -15);
DISPLAY INVISIBLE (335 -15);
FORCEPROP 1 LAST HDL_POWER P3V3_AUX
J 1
(325 75);
DISPLAY 0.872340 (325 75);
PAINT GREEN (325 75);
FORCEPROP 2 LAST CDS_LIB logical_power
J 0
(325 25);
DISPLAY INVISIBLE (325 25);
FORCEPROP 1 LAST PATH I74
J 0
(375 50);
DISPLAY 0.872340 (375 50);
PAINT AQUA (375 50);
DISPLAY INVISIBLE (375 50);
FORCEADD OFFPAGE..4
(1125 1500);
FORCEPROP 2 LAST $XR2 167 
J 0
(1551 1500);
DISPLAY 0.638298 (1551 1500);
PAINT MONO (1551 1500);
FORCEPROP 2 LAST $XR1 212 
J 0
(1431 1500);
DISPLAY 0.638298 (1431 1500);
PAINT MONO (1431 1500);
FORCEPROP 2 LAST $XR0 166 
J 0
(1311 1500);
DISPLAY 0.638298 (1311 1500);
PAINT MONO (1311 1500);
FORCEPROP 2 LAST CDS_LIB standard
J 0
(1125 1500);
DISPLAY INVISIBLE (1125 1500);
FORCEPROP 1 LAST OFFPAGE TRUE
J 0
(1450 1375);
DISPLAY 0.872340 (1450 1375);
PAINT GREEN (1450 1375);
DISPLAY INVISIBLE (1450 1375);
FORCEPROP 1 LAST COMMENT_BODY TRUE
J 0
(1100 1400);
DISPLAY 0.872340 (1100 1400);
PAINT GREEN (1100 1400);
DISPLAY INVISIBLE (1100 1400);
FORCEPROP 2 LAST PATH I75
J 0
(1575 1550);
DISPLAY 1.021277 (1575 1550);
DISPLAY INVISIBLE (1575 1550);
FORCEADD OFFPAGE..4
(100 1800);
FORCEPROP 2 LAST $XR0 166 
J 0
(286 1800);
DISPLAY 0.638298 (286 1800);
PAINT MONO (286 1800);
FORCEPROP 2 LAST CDS_LIB standard
J 0
(100 1800);
DISPLAY INVISIBLE (100 1800);
FORCEPROP 1 LAST OFFPAGE TRUE
J 0
(425 1675);
DISPLAY 0.872340 (425 1675);
PAINT GREEN (425 1675);
DISPLAY INVISIBLE (425 1675);
FORCEPROP 1 LAST COMMENT_BODY TRUE
J 0
(75 1700);
DISPLAY 0.872340 (75 1700);
PAINT GREEN (75 1700);
DISPLAY INVISIBLE (75 1700);
FORCEPROP 2 LAST PATH I76
J 0
(300 1850);
DISPLAY 1.021277 (300 1850);
DISPLAY INVISIBLE (300 1850);
FORCEADD OFFPAGE..2
(175 1950);
FORCEPROP 2 LAST $XR0 167 
J 0
(364 1950);
DISPLAY 0.638298 (364 1950);
PAINT MONO (364 1950);
FORCEPROP 2 LAST CDS_LIB standard
J 0
(175 1950);
DISPLAY INVISIBLE (175 1950);
FORCEPROP 1 LAST OFFPAGE TRUE
J 0
(500 1825);
DISPLAY 0.872340 (500 1825);
PAINT GREEN (500 1825);
DISPLAY INVISIBLE (500 1825);
FORCEPROP 1 LAST COMMENT_BODY TRUE
J 0
(130 1855);
DISPLAY 0.872340 (130 1855);
PAINT GREEN (130 1855);
DISPLAY INVISIBLE (130 1855);
FORCEPROP 2 LAST PATH I77
J 0
(375 2000);
DISPLAY 1.021277 (375 2000);
DISPLAY INVISIBLE (375 2000);
FORCEADD OFFPAGE..2
(175 2000);
FORCEPROP 2 LAST $XR0 167 
J 0
(364 2000);
DISPLAY 0.638298 (364 2000);
PAINT MONO (364 2000);
FORCEPROP 2 LAST CDS_LIB standard
J 0
(175 2000);
DISPLAY INVISIBLE (175 2000);
FORCEPROP 1 LAST OFFPAGE TRUE
J 0
(500 1875);
DISPLAY 0.872340 (500 1875);
PAINT GREEN (500 1875);
DISPLAY INVISIBLE (500 1875);
FORCEPROP 1 LAST COMMENT_BODY TRUE
J 0
(130 1905);
DISPLAY 0.872340 (130 1905);
PAINT GREEN (130 1905);
DISPLAY INVISIBLE (130 1905);
FORCEPROP 2 LAST PATH I78
J 0
(375 2050);
DISPLAY 1.021277 (375 2050);
DISPLAY INVISIBLE (375 2050);
FORCEADD OFFPAGE..2
(175 2150);
FORCEPROP 2 LAST $XR0 167 
J 0
(364 2150);
DISPLAY 0.638298 (364 2150);
PAINT MONO (364 2150);
FORCEPROP 2 LAST CDS_LIB standard
J 0
(175 2150);
DISPLAY INVISIBLE (175 2150);
FORCEPROP 1 LAST OFFPAGE TRUE
J 0
(500 2025);
DISPLAY 0.872340 (500 2025);
PAINT GREEN (500 2025);
DISPLAY INVISIBLE (500 2025);
FORCEPROP 1 LAST COMMENT_BODY TRUE
J 0
(130 2055);
DISPLAY 0.872340 (130 2055);
PAINT GREEN (130 2055);
DISPLAY INVISIBLE (130 2055);
FORCEPROP 2 LAST PATH I79
J 0
(375 2200);
DISPLAY 1.021277 (375 2200);
DISPLAY INVISIBLE (375 2200);
FORCEADD Q_RES..2
(-3075 -2575);
FORCEPROP 1 LAST PART_NUMBER CS21002FB06
J 0
(-3035 -2700);
DISPLAY 0.638298 (-3035 -2700);
DISPLAY INVISIBLE (-3035 -2700);
FORCEPROP 1 LAST MATERIAL CHIP
J 0
(-3035 -2650);
DISPLAY 0.638298 (-3035 -2650);
FORCEPROP 1 LAST WATTAGE 1/16W
J 0
(-3035 -2600);
DISPLAY 0.638298 (-3035 -2600);
FORCEPROP 1 LAST PACK_TYPE 0402LF
J 0
(-3035 -2750);
DISPLAY 0.638298 (-3035 -2750);
FORCEPROP 1 LAST TOLERANCE 1%
J 0
(-3030 -2550);
DISPLAY 0.638298 (-3030 -2550);
FORCEPROP 1 LAST VALUE 1K
J 0
(-3030 -2500);
DISPLAY 0.638298 (-3030 -2500);
FORCEPROP 2 LAST ROOM PCIE REDRIVER1_BOM1
J 0
(-3025 -2400);
DISPLAY 0.808511 (-3025 -2400);
FORCEPROP 1 LAST $LOCATION R3278
J 0
(-3030 -2450);
DISPLAY 0.978723 (-3030 -2450);
FORCEPROP 1 LASTPIN (-3075 -2475) $PN 1
J 0
(-3070 -2513);
DISPLAY 0.787234 (-3070 -2513);
PAINT MONO (-3070 -2513);
FORCEPROP 1 LASTPIN (-3075 -2675) $PN 2
J 0
(-3070 -2665);
DISPLAY 0.787234 (-3070 -2665);
PAINT MONO (-3070 -2665);
FORCEPROP 2 LAST CDS_LIB pure_quanta
J 0
(-3075 -2575);
DISPLAY INVISIBLE (-3075 -2575);
FORCEPROP 1 LAST PATH I8
J 0
(-3025 -2400);
DISPLAY 0.978723 (-3025 -2400);
PAINT WHITE (-3025 -2400);
DISPLAY INVISIBLE (-3025 -2400);
FORCEPROP 0 LAST CDS_LOCATION R3278
J 0
(-3025 -2400);
DISPLAY 1.021277 (-3025 -2400);
DISPLAY INVISIBLE (-3025 -2400);
FORCEPROP 0 LAST $SEC 1
J 0
(-3025 -2400);
DISPLAY 0.680851 (-3025 -2400);
PAINT MONO (-3025 -2400);
DISPLAY INVISIBLE (-3025 -2400);
FORCEPROP 0 LAST CDS_SEC 1
J 0
(-3025 -2400);
DISPLAY 1.021277 (-3025 -2400);
DISPLAY INVISIBLE (-3025 -2400);
FORCEADD OFFPAGE..2
(175 2200);
FORCEPROP 2 LAST $XR0 167 
J 0
(364 2200);
DISPLAY 0.638298 (364 2200);
PAINT MONO (364 2200);
FORCEPROP 2 LAST CDS_LIB standard
J 0
(175 2200);
DISPLAY INVISIBLE (175 2200);
FORCEPROP 1 LAST OFFPAGE TRUE
J 0
(500 2075);
DISPLAY 0.872340 (500 2075);
PAINT GREEN (500 2075);
DISPLAY INVISIBLE (500 2075);
FORCEPROP 1 LAST COMMENT_BODY TRUE
J 0
(130 2105);
DISPLAY 0.872340 (130 2105);
PAINT GREEN (130 2105);
DISPLAY INVISIBLE (130 2105);
FORCEPROP 2 LAST PATH I80
J 0
(375 2250);
DISPLAY 1.021277 (375 2250);
DISPLAY INVISIBLE (375 2250);
FORCEADD UNIVERSAL_GND..1
(1850 1150);
FORCEPROP 3 LASTPIN (1850 1200) SIG_NAME GND\g
J 0
(1860 1210);
DISPLAY 0.659574 (1860 1210);
PAINT MONO (1860 1210);
DISPLAY INVISIBLE (1860 1210);
FORCEPROP 2 LAST ROOM IO_SLOT
J 1
(1625 1225);
DISPLAY 0.744681 (1625 1225);
DISPLAY INVISIBLE (1625 1225);
FORCEPROP 2 LAST CDS_LIB logical_power
J 0
(1850 1150);
DISPLAY INVISIBLE (1850 1150);
FORCEPROP 1 LAST HDL_POWER GND
J 1
(1875 1075);
DISPLAY 0.872340 (1875 1075);
PAINT GREEN (1875 1075);
DISPLAY INVISIBLE (1875 1075);
FORCEPROP 1 LAST PATH I81
J 0
(1925 1150);
DISPLAY 0.872340 (1925 1150);
PAINT AQUA (1925 1150);
DISPLAY INVISIBLE (1925 1150);
FORCEADD Q_RES..2
(1850 1375);
FORCEPROP 1 LAST PART_NUMBER CS24702FB06
J 0
(1890 1250);
DISPLAY 0.787234 (1890 1250);
DISPLAY INVISIBLE (1890 1250);
FORCEPROP 1 LAST TOLERANCE 1%
J 0
(1895 1400);
DISPLAY 0.787234 (1895 1400);
FORCEPROP 1 LAST PACK_TYPE 0402LF
J 0
(1890 1200);
DISPLAY 0.787234 (1890 1200);
FORCEPROP 1 LAST WATTAGE 1/16W
J 0
(1890 1350);
DISPLAY 0.787234 (1890 1350);
FORCEPROP 1 LAST MATERIAL EMPTY
J 0
(1890 1300);
DISPLAY 0.787234 (1890 1300);
FORCEPROP 1 LAST VALUE 4.7K
J 0
(1895 1450);
DISPLAY 0.787234 (1895 1450);
FORCEPROP 1 LAST $LOCATION R3291
J 0
(1900 1500);
DISPLAY 0.978723 (1900 1500);
FORCEPROP 1 LASTPIN (1850 1475) $PN 1
J 0
(1855 1437);
DISPLAY 0.787234 (1855 1437);
PAINT MONO (1855 1437);
FORCEPROP 1 LASTPIN (1850 1275) $PN 2
J 0
(1855 1285);
DISPLAY 0.787234 (1855 1285);
PAINT MONO (1855 1285);
FORCEPROP 2 LAST CDS_LIB pure_quanta
J 0
(1850 1375);
DISPLAY INVISIBLE (1850 1375);
FORCEPROP 1 LAST PATH I82
J 0
(1900 1550);
DISPLAY 0.978723 (1900 1550);
PAINT WHITE (1900 1550);
DISPLAY INVISIBLE (1900 1550);
FORCEPROP 0 LAST CDS_LOCATION R3291
J 0
(1900 1550);
DISPLAY 1.021277 (1900 1550);
DISPLAY INVISIBLE (1900 1550);
FORCEPROP 0 LAST $SEC 1
J 0
(1900 1550);
DISPLAY 0.680851 (1900 1550);
PAINT MONO (1900 1550);
DISPLAY INVISIBLE (1900 1550);
FORCEPROP 0 LAST CDS_SEC 1
J 0
(1900 1550);
DISPLAY 1.021277 (1900 1550);
DISPLAY INVISIBLE (1900 1550);
FORCEADD UNIVERSAL_GND..1
(3100 150);
FORCEPROP 3 LASTPIN (3100 200) SIG_NAME GND\g
J 0
(3110 210);
DISPLAY 0.659574 (3110 210);
PAINT MONO (3110 210);
DISPLAY INVISIBLE (3110 210);
FORCEPROP 2 LAST CDS_LIB logical_power
J 0
(3100 150);
PAINT MONO (3100 150);
DISPLAY INVISIBLE (3100 150);
FORCEPROP 2 LAST ROOM IO_SLOT
J 1
(2875 225);
DISPLAY 0.744681 (2875 225);
DISPLAY INVISIBLE (2875 225);
FORCEPROP 1 LAST HDL_POWER GND
J 1
(3125 75);
DISPLAY 0.872340 (3125 75);
PAINT GREEN (3125 75);
DISPLAY INVISIBLE (3125 75);
FORCEPROP 1 LAST PATH I83
J 0
(3175 150);
DISPLAY 0.872340 (3175 150);
PAINT AQUA (3175 150);
DISPLAY INVISIBLE (3175 150);
FORCEADD Q_RES..2
(3100 375);
FORCEPROP 1 LAST PART_NUMBER CS24702FB06
J 0
(3140 250);
DISPLAY 0.787234 (3140 250);
DISPLAY INVISIBLE (3140 250);
FORCEPROP 1 LAST PACK_TYPE 0402LF
J 0
(3140 200);
DISPLAY 0.787234 (3140 200);
FORCEPROP 1 LAST TOLERANCE 1%
J 0
(3145 400);
DISPLAY 0.787234 (3145 400);
FORCEPROP 1 LAST VALUE 4.7K
J 0
(3145 450);
DISPLAY 0.787234 (3145 450);
FORCEPROP 1 LAST WATTAGE 1/16W
J 0
(3140 350);
DISPLAY 0.787234 (3140 350);
FORCEPROP 1 LAST MATERIAL EMPTY
J 0
(3140 300);
DISPLAY 0.787234 (3140 300);
PAINT RED (3140 300);
FORCEPROP 1 LAST $LOCATION R3265
J 0
(3145 500);
DISPLAY 0.978723 (3145 500);
FORCEPROP 1 LASTPIN (3100 475) $PN 1
J 0
(3105 437);
DISPLAY 0.787234 (3105 437);
FORCEPROP 1 LASTPIN (3100 275) $PN 2
J 0
(3105 285);
DISPLAY 0.787234 (3105 285);
FORCEPROP 2 LAST CDS_LIB pure_quanta
J 0
(3100 375);
PAINT MONO (3100 375);
DISPLAY INVISIBLE (3100 375);
FORCEPROP 1 LAST PATH I84
J 0
(3150 550);
DISPLAY 0.978723 (3150 550);
PAINT WHITE (3150 550);
DISPLAY INVISIBLE (3150 550);
FORCEPROP 2 LAST CDS_LOCATION R3265
J 0
(3150 600);
DISPLAY 1.021277 (3150 600);
DISPLAY INVISIBLE (3150 600);
FORCEPROP 2 LAST $SEC 1
J 0
(3150 600);
DISPLAY 0.680851 (3150 600);
PAINT MONO (3150 600);
DISPLAY INVISIBLE (3150 600);
FORCEPROP 2 LAST CDS_SEC 1
J 0
(3150 600);
DISPLAY 1.021277 (3150 600);
DISPLAY INVISIBLE (3150 600);
FORCEADD Q_RES..2
(3100 900);
FORCEPROP 1 LAST PART_NUMBER CS24702FB06
J 0
(3140 775);
DISPLAY 0.787234 (3140 775);
DISPLAY INVISIBLE (3140 775);
FORCEPROP 1 LAST TOLERANCE 1%
J 0
(3145 925);
DISPLAY 0.787234 (3145 925);
FORCEPROP 1 LAST PACK_TYPE 0402LF
J 0
(3140 725);
DISPLAY 0.787234 (3140 725);
FORCEPROP 1 LAST WATTAGE 1/16W
J 0
(3140 875);
DISPLAY 0.787234 (3140 875);
FORCEPROP 1 LAST MATERIAL CHIP
J 0
(3140 825);
DISPLAY 0.787234 (3140 825);
FORCEPROP 1 LAST VALUE 4.7K
J 0
(3145 975);
DISPLAY 0.787234 (3145 975);
FORCEPROP 2 LAST ROOM PCIE REDRIVER1_BOM1
J 0
(3150 1075);
DISPLAY 1.021277 (3150 1075);
FORCEPROP 1 LAST $LOCATION R3292
J 0
(3145 1025);
DISPLAY 0.978723 (3145 1025);
FORCEPROP 1 LASTPIN (3100 1000) $PN 1
J 0
(3105 962);
DISPLAY 0.787234 (3105 962);
PAINT MONO (3105 962);
FORCEPROP 1 LASTPIN (3100 800) $PN 2
J 0
(3105 810);
DISPLAY 0.787234 (3105 810);
PAINT MONO (3105 810);
FORCEPROP 2 LAST CDS_LIB pure_quanta
J 0
(3100 900);
DISPLAY INVISIBLE (3100 900);
FORCEPROP 1 LAST PATH I85
J 0
(3150 1075);
DISPLAY 0.978723 (3150 1075);
PAINT WHITE (3150 1075);
DISPLAY INVISIBLE (3150 1075);
FORCEPROP 0 LAST CDS_LOCATION R3292
J 0
(3150 1075);
DISPLAY 1.021277 (3150 1075);
DISPLAY INVISIBLE (3150 1075);
FORCEPROP 0 LAST $SEC 1
J 0
(3150 1075);
DISPLAY 0.680851 (3150 1075);
PAINT MONO (3150 1075);
DISPLAY INVISIBLE (3150 1075);
FORCEPROP 0 LAST CDS_SEC 1
J 0
(3150 1075);
DISPLAY 1.021277 (3150 1075);
DISPLAY INVISIBLE (3150 1075);
FORCEADD UNIVERSAL_POWER..1
(3100 1200);
FORCEPROP 3 LASTPIN (3100 1150) SIG_NAME P3V3_AUX\g
J 0
(3110 1160);
DISPLAY 0.659574 (3110 1160);
PAINT MONO (3110 1160);
DISPLAY INVISIBLE (3110 1160);
FORCEPROP 1 LAST HDL_POWER P3V3_AUX
J 1
(3100 1250);
DISPLAY 0.872340 (3100 1250);
PAINT GREEN (3100 1250);
FORCEPROP 2 LAST CDS_LIB logical_power
J 0
(3100 1200);
PAINT MONO (3100 1200);
DISPLAY INVISIBLE (3100 1200);
FORCEPROP 1 LAST PATH I86
J 0
(3150 1225);
DISPLAY 0.872340 (3150 1225);
PAINT AQUA (3150 1225);
DISPLAY INVISIBLE (3150 1225);
FORCEADD UNIVERSAL_GND..1
(3100 1625);
FORCEPROP 3 LASTPIN (3100 1675) SIG_NAME GND\g
J 0
(3110 1685);
DISPLAY 0.659574 (3110 1685);
PAINT MONO (3110 1685);
DISPLAY INVISIBLE (3110 1685);
FORCEPROP 2 LAST ROOM IO_SLOT
J 1
(2875 1700);
DISPLAY 0.744681 (2875 1700);
DISPLAY INVISIBLE (2875 1700);
FORCEPROP 2 LAST CDS_LIB logical_power
J 0
(3100 1625);
PAINT MONO (3100 1625);
DISPLAY INVISIBLE (3100 1625);
FORCEPROP 1 LAST HDL_POWER GND
J 1
(3125 1550);
DISPLAY 0.872340 (3125 1550);
PAINT GREEN (3125 1550);
DISPLAY INVISIBLE (3125 1550);
FORCEPROP 1 LAST PATH I87
J 0
(3175 1625);
DISPLAY 0.872340 (3175 1625);
PAINT AQUA (3175 1625);
DISPLAY INVISIBLE (3175 1625);
FORCEADD Q_RES..2
(3100 1850);
FORCEPROP 1 LAST PART_NUMBER CS24702FB06
J 0
(3140 1725);
DISPLAY 0.787234 (3140 1725);
DISPLAY INVISIBLE (3140 1725);
FORCEPROP 1 LAST TOLERANCE 1%
J 0
(3145 1875);
DISPLAY 0.787234 (3145 1875);
FORCEPROP 1 LAST VALUE 4.7K
J 0
(3145 1925);
DISPLAY 0.787234 (3145 1925);
FORCEPROP 1 LAST WATTAGE 1/16W
J 0
(3140 1825);
DISPLAY 0.787234 (3140 1825);
FORCEPROP 1 LAST MATERIAL EMPTY
J 0
(3140 1775);
DISPLAY 0.787234 (3140 1775);
FORCEPROP 1 LAST PACK_TYPE 0402LF
J 0
(3140 1675);
DISPLAY 0.787234 (3140 1675);
FORCEPROP 1 LAST $LOCATION R3293
J 0
(3145 1975);
DISPLAY 0.978723 (3145 1975);
FORCEPROP 1 LASTPIN (3100 1950) $PN 1
J 0
(3105 1912);
DISPLAY 0.787234 (3105 1912);
PAINT MONO (3105 1912);
FORCEPROP 1 LASTPIN (3100 1750) $PN 2
J 0
(3105 1760);
DISPLAY 0.787234 (3105 1760);
PAINT MONO (3105 1760);
FORCEPROP 2 LAST CDS_LIB pure_quanta
J 0
(3100 1850);
DISPLAY INVISIBLE (3100 1850);
FORCEPROP 1 LAST PATH I88
J 0
(3150 2025);
DISPLAY 0.978723 (3150 2025);
PAINT WHITE (3150 2025);
DISPLAY INVISIBLE (3150 2025);
FORCEPROP 0 LAST CDS_LOCATION R3293
J 0
(3150 2025);
DISPLAY 1.021277 (3150 2025);
DISPLAY INVISIBLE (3150 2025);
FORCEPROP 0 LAST $SEC 1
J 0
(3150 2025);
DISPLAY 0.680851 (3150 2025);
PAINT MONO (3150 2025);
DISPLAY INVISIBLE (3150 2025);
FORCEPROP 0 LAST CDS_SEC 1
J 0
(3150 2025);
DISPLAY 1.021277 (3150 2025);
DISPLAY INVISIBLE (3150 2025);
FORCEADD Q_RES..2
(3100 2375);
FORCEPROP 1 LAST PART_NUMBER CS24702FB06
J 0
(3140 2250);
DISPLAY 0.787234 (3140 2250);
DISPLAY INVISIBLE (3140 2250);
FORCEPROP 1 LAST TOLERANCE 1%
J 0
(3145 2400);
DISPLAY 0.787234 (3145 2400);
FORCEPROP 1 LAST VALUE 4.7K
J 0
(3145 2450);
DISPLAY 0.787234 (3145 2450);
FORCEPROP 1 LAST WATTAGE 1/16W
J 0
(3140 2350);
DISPLAY 0.787234 (3140 2350);
FORCEPROP 1 LAST MATERIAL CHIP
J 0
(3140 2300);
DISPLAY 0.787234 (3140 2300);
FORCEPROP 1 LAST PACK_TYPE 0402LF
J 0
(3140 2200);
DISPLAY 0.787234 (3140 2200);
FORCEPROP 2 LAST ROOM PCIE REDRIVER1_BOM1
J 0
(3150 2550);
DISPLAY 1.021277 (3150 2550);
FORCEPROP 1 LAST $LOCATION R3266
J 0
(3145 2500);
DISPLAY 0.978723 (3145 2500);
FORCEPROP 1 LASTPIN (3100 2475) $PN 1
J 0
(3105 2437);
DISPLAY 0.787234 (3105 2437);
FORCEPROP 1 LASTPIN (3100 2275) $PN 2
J 0
(3105 2285);
DISPLAY 0.787234 (3105 2285);
FORCEPROP 2 LAST CDS_LIB pure_quanta
J 0
(3100 2375);
PAINT MONO (3100 2375);
DISPLAY INVISIBLE (3100 2375);
FORCEPROP 1 LAST PATH I89
J 0
(3150 2550);
DISPLAY 0.978723 (3150 2550);
PAINT WHITE (3150 2550);
DISPLAY INVISIBLE (3150 2550);
FORCEPROP 2 LAST CDS_LOCATION R3266
J 0
(3150 2600);
DISPLAY 1.021277 (3150 2600);
DISPLAY INVISIBLE (3150 2600);
FORCEPROP 2 LAST $SEC 1
J 0
(3150 2600);
DISPLAY 0.680851 (3150 2600);
PAINT MONO (3150 2600);
DISPLAY INVISIBLE (3150 2600);
FORCEPROP 2 LAST CDS_SEC 1
J 0
(3150 2600);
DISPLAY 1.021277 (3150 2600);
DISPLAY INVISIBLE (3150 2600);
FORCEADD Q_RES..2
(-3950 -2000);
FORCEPROP 1 LAST PART_NUMBER CS21002FB06
J 0
(-3910 -2125);
DISPLAY 0.638298 (-3910 -2125);
DISPLAY INVISIBLE (-3910 -2125);
FORCEPROP 1 LAST MATERIAL EMPTY
J 0
(-3910 -2075);
DISPLAY 0.638298 (-3910 -2075);
PAINT RED (-3910 -2075);
FORCEPROP 1 LAST WATTAGE 1/16W
J 0
(-3910 -2025);
DISPLAY 0.638298 (-3910 -2025);
FORCEPROP 1 LAST VALUE 1K
J 0
(-3905 -1925);
DISPLAY 0.638298 (-3905 -1925);
FORCEPROP 1 LAST TOLERANCE 1%
J 0
(-3905 -1975);
DISPLAY 0.638298 (-3905 -1975);
FORCEPROP 1 LAST PACK_TYPE 0402LF
J 0
(-3910 -2175);
DISPLAY 0.638298 (-3910 -2175);
FORCEPROP 1 LAST $LOCATION R3271
J 0
(-3905 -1875);
DISPLAY 0.638298 (-3905 -1875);
FORCEPROP 1 LASTPIN (-3950 -1900) $PN 1
J 0
(-3945 -1938);
DISPLAY 0.787234 (-3945 -1938);
PAINT MONO (-3945 -1938);
FORCEPROP 1 LASTPIN (-3950 -2100) $PN 2
J 0
(-3945 -2090);
DISPLAY 0.787234 (-3945 -2090);
PAINT MONO (-3945 -2090);
FORCEPROP 2 LAST CDS_LIB pure_quanta
J 0
(-3950 -2000);
DISPLAY INVISIBLE (-3950 -2000);
FORCEPROP 1 LAST PATH I9
J 0
(-3900 -1825);
DISPLAY 0.978723 (-3900 -1825);
PAINT WHITE (-3900 -1825);
DISPLAY INVISIBLE (-3900 -1825);
FORCEPROP 0 LAST CDS_LOCATION R3271
J 0
(-3900 -1825);
DISPLAY 1.021277 (-3900 -1825);
DISPLAY INVISIBLE (-3900 -1825);
FORCEPROP 0 LAST $SEC 1
J 0
(-3900 -1825);
DISPLAY 0.680851 (-3900 -1825);
PAINT MONO (-3900 -1825);
DISPLAY INVISIBLE (-3900 -1825);
FORCEPROP 0 LAST CDS_SEC 1
J 0
(-3900 -1825);
DISPLAY 1.021277 (-3900 -1825);
DISPLAY INVISIBLE (-3900 -1825);
FORCEADD UNIVERSAL_POWER..1
(3100 2675);
FORCEPROP 3 LASTPIN (3100 2625) SIG_NAME P3V3_AUX\g
J 0
(3110 2635);
DISPLAY 0.659574 (3110 2635);
PAINT MONO (3110 2635);
DISPLAY INVISIBLE (3110 2635);
FORCEPROP 1 LAST HDL_POWER P3V3_AUX
J 1
(3100 2725);
DISPLAY 0.872340 (3100 2725);
PAINT GREEN (3100 2725);
FORCEPROP 2 LAST CDS_LIB logical_power
J 0
(3100 2675);
PAINT MONO (3100 2675);
DISPLAY INVISIBLE (3100 2675);
FORCEPROP 1 LAST PATH I90
J 0
(3150 2700);
DISPLAY 0.872340 (3150 2700);
PAINT AQUA (3150 2700);
DISPLAY INVISIBLE (3150 2700);
FORCEADD OFFPAGE..2
(4250 675);
FORCEPROP 2 LAST $XR2 167 
J 0
(4439 639);
DISPLAY 0.638298 (4439 639);
PAINT MONO (4439 639);
FORCEPROP 2 LAST $XR1 166 
J 0
(4559 675);
DISPLAY 0.638298 (4559 675);
PAINT MONO (4559 675);
FORCEPROP 2 LAST $XR0 212 
J 0
(4439 675);
DISPLAY 0.638298 (4439 675);
PAINT MONO (4439 675);
FORCEPROP 2 LAST CDS_LIB standard
J 0
(4250 675);
PAINT MONO (4250 675);
DISPLAY INVISIBLE (4250 675);
FORCEPROP 1 LAST OFFPAGE TRUE
J 0
(4575 550);
DISPLAY 0.872340 (4575 550);
PAINT GREEN (4575 550);
DISPLAY INVISIBLE (4575 550);
FORCEPROP 1 LAST COMMENT_BODY TRUE
J 0
(4205 580);
DISPLAY 0.872340 (4205 580);
PAINT GREEN (4205 580);
DISPLAY INVISIBLE (4205 580);
FORCEPROP 2 LAST PATH I91
J 0
(4575 725);
DISPLAY 1.021277 (4575 725);
DISPLAY INVISIBLE (4575 725);
FORCEADD OFFPAGE..2
(3825 2125);
FORCEPROP 2 LAST $XR0 166 
J 0
(4014 2125);
DISPLAY 0.638298 (4014 2125);
PAINT MONO (4014 2125);
FORCEPROP 2 LAST CDS_LIB standard
J 0
(3825 2125);
PAINT MONO (3825 2125);
DISPLAY INVISIBLE (3825 2125);
FORCEPROP 1 LAST OFFPAGE TRUE
J 0
(4150 2000);
DISPLAY 0.872340 (4150 2000);
PAINT GREEN (4150 2000);
DISPLAY INVISIBLE (4150 2000);
FORCEPROP 1 LAST COMMENT_BODY TRUE
J 0
(3780 2030);
DISPLAY 0.872340 (3780 2030);
PAINT GREEN (3780 2030);
DISPLAY INVISIBLE (3780 2030);
FORCEPROP 2 LAST PATH I92
J 0
(4025 2175);
DISPLAY 1.021277 (4025 2175);
DISPLAY INVISIBLE (4025 2175);
FORCEADD QUANTA_TITLE_BLOCK_C..1
(4675 -3350);
FORCEPROP 0 LAST CDS_CON_LAST_MODIFIED Fri Aug 25 14:02:37 2023
J 0
(2790 -3335);
PAINT MONO (2790 -3335);
DISPLAY INVISIBLE (2790 -3335);
FORCEPROP 2 LAST CUSTOM_TXT_CDS <XR_PAGE_TITLE>
J 0
(-3215 1900);
DISPLAY 0.638298 (-3215 1900);
PAINT PINK (-3215 1900);
DISPLAY INVISIBLE (-3215 1900);
FORCEPROP 2 LAST CUSTOM_TXT_CDS <CON_LAST_MODIFIED>
J 0
(2790 -3335);
DISPLAY 0.978723 (2790 -3335);
FORCEPROP 2 LAST CUSTOM_TXT_CDS <NAME_1>
J 0
(1500 -3175);
FORCEPROP 2 LAST CUSTOM_TXT_CDS <NAME_2>
J 0
(1500 -3300);
FORCEPROP 2 LAST CUSTOM_TXT_CDS <Q_PROJ>
J 0
(2293 -3248);
DISPLAY 1.212766 (2293 -3248);
FORCEPROP 2 LAST CUSTOM_TXT_CDS <Q_NUMBER>
J 0
(3272 -3247);
DISPLAY 1.212766 (3272 -3247);
FORCEPROP 2 LAST CUSTOM_TXT_CDS <CON_PAGE_NUM> OF <CON_TOTAL_PAGES>
J 0
(4229 -3332);
DISPLAY 0.978723 (4229 -3332);
FORCEPROP 1 LAST CUSTOM_TXT_CDS <Q_REV>
J 0
(4491 -3247);
DISPLAY 1.212766 (4491 -3247);
FORCEPROP 1 LAST Q_TITLE FPGA- PCIE - RE-DRIVER
J 0
(-4591 -3349);
DISPLAY 2.446809 (-4591 -3349);
PAINT GREEN (-4591 -3349);
FORCEPROP 1 LAST Q_DEPT 
J 1
(912 -3301);
DISPLAY 1.957447 (912 -3301);
PAINT GREEN (912 -3301);
FORCEPROP 2 LAST CDS_XR_PAGE_TITLE CR-166 : @S9S_MB_2U_LIB.S9S_MB_2U(SCH_1):PAGE166
J 0
(-3215 1900);
DISPLAY 0.638298 (-3215 1900);
PAINT PINK (-3215 1900);
DISPLAY INVISIBLE (-3215 1900);
FORCEPROP 1 LAST COMMENT_BODY TRUE
J 0
(4687 -3363);
DISPLAY 0.978723 (4687 -3363);
PAINT GREEN (4687 -3363);
DISPLAY INVISIBLE (4687 -3363);
FORCEPROP 2 LAST CDS_LIB pure_quanta
J 0
(4675 -3350);
PAINT MONO (4675 -3350);
DISPLAY INVISIBLE (4675 -3350);
FORCEPROP 1 LAST CDS_LMAN_SYM_OUTLINE -9475,6775,100,-125
J 0
(4675 -3350);
DISPLAY 0.468085 (4675 -3350);
PAINT GREEN (4675 -3350);
DISPLAY INVISIBLE (4675 -3350);
FORCEPROP 2 LAST PAGE_BORDER TRUE
J 0
(-3215 1900);
DISPLAY 0.638298 (-3215 1900);
PAINT PINK (-3215 1900);
DISPLAY INVISIBLE (-3215 1900);
FORCEADD DNS..2
(3100 1825);
PAINT RED (3100 1825);
FORCEPROP 2 LAST CDS_LIB mstr_misc
J 0
(3100 1825);
DISPLAY INVISIBLE (3100 1825);
FORCEPROP 1 LAST COMMENT_BODY TRUE
R 1
J 0
(3175 1600);
DISPLAY 0.872340 (3175 1600);
PAINT GREEN (3175 1600);
DISPLAY INVISIBLE (3175 1600);
FORCEADD DNS..2
(3100 350);
PAINT RED (3100 350);
FORCEPROP 2 LAST CDS_LIB mstr_misc
J 0
(3100 350);
DISPLAY INVISIBLE (3100 350);
FORCEPROP 1 LAST COMMENT_BODY TRUE
R 1
J 0
(3175 125);
DISPLAY 0.872340 (3175 125);
PAINT GREEN (3175 125);
DISPLAY INVISIBLE (3175 125);
FORCEADD DNS..2
(1850 1350);
PAINT RED (1850 1350);
FORCEPROP 2 LAST CDS_LIB mstr_misc
J 0
(1850 1350);
DISPLAY INVISIBLE (1850 1350);
FORCEPROP 1 LAST COMMENT_BODY TRUE
R 1
J 0
(1925 1125);
DISPLAY 0.872340 (1925 1125);
PAINT GREEN (1925 1125);
DISPLAY INVISIBLE (1925 1125);
FORCEADD DNS..2
(1200 -300);
PAINT RED (1200 -300);
FORCEPROP 2 LAST CDS_LIB mstr_misc
J 0
(1200 -300);
DISPLAY INVISIBLE (1200 -300);
FORCEPROP 1 LAST COMMENT_BODY TRUE
R 1
J 0
(1275 -525);
DISPLAY 0.872340 (1275 -525);
PAINT GREEN (1275 -525);
DISPLAY INVISIBLE (1275 -525);
FORCEADD DNS..2
(1200 -875);
PAINT RED (1200 -875);
FORCEPROP 2 LAST CDS_LIB mstr_misc
J 0
(1200 -875);
DISPLAY INVISIBLE (1200 -875);
FORCEPROP 1 LAST COMMENT_BODY TRUE
R 1
J 0
(1275 -1100);
DISPLAY 0.872340 (1275 -1100);
PAINT GREEN (1275 -1100);
DISPLAY INVISIBLE (1275 -1100);
FORCEADD DNS..2
(800 -850);
PAINT RED (800 -850);
FORCEPROP 2 LAST CDS_LIB mstr_misc
J 0
(800 -850);
DISPLAY INVISIBLE (800 -850);
FORCEPROP 1 LAST COMMENT_BODY TRUE
R 1
J 0
(875 -1075);
DISPLAY 0.872340 (875 -1075);
PAINT GREEN (875 -1075);
DISPLAY INVISIBLE (875 -1075);
FORCEADD DNS..2
(325 -300);
PAINT RED (325 -300);
FORCEPROP 2 LAST CDS_LIB mstr_misc
J 0
(325 -300);
DISPLAY INVISIBLE (325 -300);
FORCEPROP 1 LAST COMMENT_BODY TRUE
R 1
J 0
(400 -525);
DISPLAY 0.872340 (400 -525);
PAINT GREEN (400 -525);
DISPLAY INVISIBLE (400 -525);
FORCEADD DNS..2
(325 -825);
PAINT RED (325 -825);
FORCEPROP 2 LAST CDS_LIB mstr_misc
J 0
(325 -825);
DISPLAY INVISIBLE (325 -825);
FORCEPROP 1 LAST COMMENT_BODY TRUE
R 1
J 0
(400 -1050);
DISPLAY 0.872340 (400 -1050);
PAINT GREEN (400 -1050);
DISPLAY INVISIBLE (400 -1050);
FORCEADD DNS..2
(-50 -825);
PAINT RED (-50 -825);
FORCEPROP 2 LAST CDS_LIB mstr_misc
J 0
(-50 -825);
DISPLAY INVISIBLE (-50 -825);
FORCEPROP 1 LAST COMMENT_BODY TRUE
R 1
J 0
(25 -1050);
DISPLAY 0.872340 (25 -1050);
PAINT GREEN (25 -1050);
DISPLAY INVISIBLE (25 -1050);
FORCEADD DNS..2
(-825 -2050);
PAINT RED (-825 -2050);
FORCEPROP 2 LAST CDS_LIB mstr_misc
J 0
(-825 -2050);
DISPLAY INVISIBLE (-825 -2050);
FORCEPROP 1 LAST COMMENT_BODY TRUE
R 1
J 0
(-750 -2275);
DISPLAY 0.872340 (-750 -2275);
PAINT GREEN (-750 -2275);
DISPLAY INVISIBLE (-750 -2275);
FORCEADD DNS..2
(-1700 -2050);
PAINT RED (-1700 -2050);
FORCEPROP 2 LAST CDS_LIB mstr_misc
J 0
(-1700 -2050);
DISPLAY INVISIBLE (-1700 -2050);
FORCEPROP 1 LAST COMMENT_BODY TRUE
R 1
J 0
(-1625 -2275);
DISPLAY 0.872340 (-1625 -2275);
PAINT GREEN (-1625 -2275);
DISPLAY INVISIBLE (-1625 -2275);
FORCEADD DNS..2
(-1225 -2600);
PAINT RED (-1225 -2600);
FORCEPROP 2 LAST CDS_LIB mstr_misc
J 0
(-1225 -2600);
DISPLAY INVISIBLE (-1225 -2600);
FORCEPROP 1 LAST COMMENT_BODY TRUE
R 1
J 0
(-1150 -2825);
DISPLAY 0.872340 (-1150 -2825);
PAINT GREEN (-1150 -2825);
DISPLAY INVISIBLE (-1150 -2825);
FORCEADD DNS..2
(-1700 -2575);
PAINT RED (-1700 -2575);
FORCEPROP 2 LAST CDS_LIB mstr_misc
J 0
(-1700 -2575);
DISPLAY INVISIBLE (-1700 -2575);
FORCEPROP 1 LAST COMMENT_BODY TRUE
R 1
J 0
(-1625 -2800);
DISPLAY 0.872340 (-1625 -2800);
PAINT GREEN (-1625 -2800);
DISPLAY INVISIBLE (-1625 -2800);
FORCEADD DNS..2
(-2075 -2575);
PAINT RED (-2075 -2575);
FORCEPROP 2 LAST CDS_LIB mstr_misc
J 0
(-2075 -2575);
DISPLAY INVISIBLE (-2075 -2575);
FORCEPROP 1 LAST COMMENT_BODY TRUE
R 1
J 0
(-2000 -2800);
DISPLAY 0.872340 (-2000 -2800);
PAINT GREEN (-2000 -2800);
DISPLAY INVISIBLE (-2000 -2800);
FORCEADD DNS..2
(-3250 -300);
PAINT RED (-3250 -300);
FORCEPROP 2 LAST CDS_LIB mstr_misc
J 0
(-3250 -300);
DISPLAY INVISIBLE (-3250 -300);
FORCEPROP 1 LAST COMMENT_BODY TRUE
R 1
J 0
(-3175 -525);
DISPLAY 0.872340 (-3175 -525);
PAINT GREEN (-3175 -525);
DISPLAY INVISIBLE (-3175 -525);
FORCEADD DNS..2
(-3250 -875);
PAINT RED (-3250 -875);
FORCEPROP 2 LAST CDS_LIB mstr_misc
J 0
(-3250 -875);
DISPLAY INVISIBLE (-3250 -875);
FORCEPROP 1 LAST COMMENT_BODY TRUE
R 1
J 0
(-3175 -1100);
DISPLAY 0.872340 (-3175 -1100);
PAINT GREEN (-3175 -1100);
DISPLAY INVISIBLE (-3175 -1100);
FORCEADD DNS..2
(-3650 -850);
PAINT RED (-3650 -850);
FORCEPROP 2 LAST CDS_LIB mstr_misc
J 0
(-3650 -850);
DISPLAY INVISIBLE (-3650 -850);
FORCEPROP 1 LAST COMMENT_BODY TRUE
R 1
J 0
(-3575 -1075);
DISPLAY 0.872340 (-3575 -1075);
PAINT GREEN (-3575 -1075);
DISPLAY INVISIBLE (-3575 -1075);
FORCEADD DNS..2
(-3075 -2025);
PAINT RED (-3075 -2025);
FORCEPROP 2 LAST CDS_LIB mstr_misc
J 0
(-3075 -2025);
DISPLAY INVISIBLE (-3075 -2025);
FORCEPROP 1 LAST COMMENT_BODY TRUE
R 1
J 0
(-3000 -2250);
DISPLAY 0.872340 (-3000 -2250);
PAINT GREEN (-3000 -2250);
DISPLAY INVISIBLE (-3000 -2250);
FORCEADD DNS..2
(-4125 -300);
PAINT RED (-4125 -300);
FORCEPROP 2 LAST CDS_LIB mstr_misc
J 0
(-4125 -300);
DISPLAY INVISIBLE (-4125 -300);
FORCEPROP 1 LAST COMMENT_BODY TRUE
R 1
J 0
(-4050 -525);
DISPLAY 0.872340 (-4050 -525);
PAINT GREEN (-4050 -525);
DISPLAY INVISIBLE (-4050 -525);
FORCEADD DNS..2
(-4125 -825);
PAINT RED (-4125 -825);
FORCEPROP 2 LAST CDS_LIB mstr_misc
J 0
(-4125 -825);
DISPLAY INVISIBLE (-4125 -825);
FORCEPROP 1 LAST COMMENT_BODY TRUE
R 1
J 0
(-4050 -1050);
DISPLAY 0.872340 (-4050 -1050);
PAINT GREEN (-4050 -1050);
DISPLAY INVISIBLE (-4050 -1050);
FORCEADD DNS..2
(-4500 -825);
PAINT RED (-4500 -825);
FORCEPROP 2 LAST CDS_LIB mstr_misc
J 0
(-4500 -825);
DISPLAY INVISIBLE (-4500 -825);
FORCEPROP 1 LAST COMMENT_BODY TRUE
R 1
J 0
(-4425 -1050);
DISPLAY 0.872340 (-4425 -1050);
PAINT GREEN (-4425 -1050);
DISPLAY INVISIBLE (-4425 -1050);
FORCEADD DNS..2
(-3950 -2025);
PAINT RED (-3950 -2025);
FORCEPROP 2 LAST CDS_LIB mstr_misc
J 0
(-3950 -2025);
DISPLAY INVISIBLE (-3950 -2025);
FORCEPROP 1 LAST COMMENT_BODY TRUE
R 1
J 0
(-3875 -2250);
DISPLAY 0.872340 (-3875 -2250);
PAINT GREEN (-3875 -2250);
DISPLAY INVISIBLE (-3875 -2250);
FORCEADD DNS..2
(-3475 -2575);
PAINT RED (-3475 -2575);
FORCEPROP 2 LAST CDS_LIB mstr_misc
J 0
(-3475 -2575);
DISPLAY INVISIBLE (-3475 -2575);
FORCEPROP 1 LAST COMMENT_BODY TRUE
R 1
J 0
(-3400 -2800);
DISPLAY 0.872340 (-3400 -2800);
PAINT GREEN (-3400 -2800);
DISPLAY INVISIBLE (-3400 -2800);
FORCEADD DNS..2
(-3950 -2550);
PAINT RED (-3950 -2550);
FORCEPROP 2 LAST CDS_LIB mstr_misc
J 0
(-3950 -2550);
DISPLAY INVISIBLE (-3950 -2550);
FORCEPROP 1 LAST COMMENT_BODY TRUE
R 1
J 0
(-3875 -2775);
DISPLAY 0.872340 (-3875 -2775);
PAINT GREEN (-3875 -2775);
DISPLAY INVISIBLE (-3875 -2775);
FORCEADD DNS..2
(-4325 -2550);
PAINT RED (-4325 -2550);
FORCEPROP 2 LAST CDS_LIB mstr_misc
J 0
(-4325 -2550);
DISPLAY INVISIBLE (-4325 -2550);
FORCEPROP 1 LAST COMMENT_BODY TRUE
R 1
J 0
(-4250 -2775);
DISPLAY 0.872340 (-4250 -2775);
PAINT GREEN (-4250 -2775);
DISPLAY INVISIBLE (-4250 -2775);
WIRE 16 -1 (-1700 -1775)(-1700 -1825);
WIRE 16 -1 (3100 1000)(3100 1150);
WIRE 16 -1 (-1875 2700)(-1875 2575);
WIRE 16 -1 (-3950 -1750)(-3950 -1800);
WIRE 16 -1 (-4125 -25)(-4125 -75);
WIRE 16 -1 (325 -25)(325 -75);
WIRE 16 -1 (3100 2475)(3100 2625);
WIRE 16 -1 (-4325 -2825)(-4325 -2625);
WIRE 16 -1 (-3950 -2825)(-3950 -2625);
WIRE 16 -1 (-3475 -2825)(-3475 -2650);
WIRE 16 -1 (-3075 -2825)(-3075 -2675);
WIRE 16 -1 (-4500 -1100)(-4500 -900);
WIRE 16 -1 (-4125 -1100)(-4125 -900);
WIRE 16 -1 (-3650 -1100)(-3650 -925);
WIRE 16 -1 (-3250 -1100)(-3250 -950);
WIRE 16 -1 (-2075 -2850)(-2075 -2650);
WIRE 16 -1 (-1700 -2850)(-1700 -2650);
WIRE 16 -1 (-1225 -2850)(-1225 -2675);
WIRE 16 -1 (-3275 2050)(-3275 2125);
WIRE 16 -1 (-825 -2850)(-825 -2700);
WIRE 16 -1 (-50 -1100)(-50 -900);
WIRE 16 -1 (325 -1100)(325 -900);
WIRE 16 -1 (800 -1100)(800 -925);
WIRE 16 -1 (1200 -1100)(1200 -950);
WIRE 16 -1 (-775 675)(-775 850);
WIRE 16 -1 (1850 1200)(1850 1275);
WIRE 16 -1 (3100 200)(3100 275);
WIRE 16 -1 (3100 1675)(3100 1750);
WIRE 16 -1 (-1700 -1825)(-1700 -1925);
WIRE 16 -1 (-825 -1825)(-1700 -1825);
WIRE 16 -1 (-825 -1925)(-825 -1825);
WIRE 16 -1 (-50 -575)(-50 -700);
WIRE 16 -1 (325 -575)(-50 -575);
WIRE 16 -1 (325 -700)(325 -575);
WIRE 16 -1 (325 -575)(325 -525);
WIRE 16 -1 (325 -525)(325 -375);
WIRE 16 -1 (325 -525)(1625 -525);
FORCEPROP 2 LAST SIG_NAME FM_P2E_SWB
J 0
(1240 -515);
DISPLAY 0.638298 (1240 -515);
PAINT WHITE (1240 -515);
WIRE 16 -1 (-1750 1050)(-2950 1050);
FORCEPROP 2 LAST SIG_NAME P2E_MB_BMC_RX_R1_DN<0>
J 0
(-2676 1060);
DISPLAY 0.553191 (-2676 1060);
PAINT WHITE (-2676 1060);
WIRE 16 -1 (-1750 1100)(-2950 1100);
FORCEPROP 2 LAST SIG_NAME P2E_MB_BMC_RX_R1_DP<0>
J 0
(-2676 1110);
DISPLAY 0.553191 (-2676 1110);
PAINT WHITE (-2676 1110);
WIRE 16 -1 (-1750 1200)(-2950 1200);
FORCEPROP 2 LAST SIG_NAME P2E_MB_BMC_TX_C_R1_DN<0>
J 0
(-2685 1210);
DISPLAY 0.553191 (-2685 1210);
PAINT WHITE (-2685 1210);
WIRE 16 -1 (-1750 1250)(-2950 1250);
FORCEPROP 2 LAST SIG_NAME P2E_MB_BMC_TX_C_R1_DP<0>
J 0
(-2685 1260);
DISPLAY 0.553191 (-2685 1260);
PAINT WHITE (-2685 1260);
WIRE 16 -1 (-1750 1350)(-2950 1350);
FORCEPROP 2 LAST SIG_NAME FM_P2E_EQB1
J 0
(-2685 1360);
DISPLAY 0.553191 (-2685 1360);
PAINT WHITE (-2685 1360);
WIRE 16 -1 (-1750 1400)(-2950 1400);
FORCEPROP 2 LAST SIG_NAME FM_P2E_EQB0
J 0
(-2685 1410);
DISPLAY 0.553191 (-2685 1410);
PAINT WHITE (-2685 1410);
WIRE 16 -1 (800 -625)(800 -725);
WIRE 16 -1 (1200 -625)(800 -625);
WIRE 16 -1 (1200 -750)(1200 -625);
WIRE 16 -1 (1200 -625)(1200 -575);
WIRE 16 -1 (1200 -375)(1200 -575);
WIRE 16 -1 (1200 -575)(1625 -575);
FORCEPROP 2 LAST SIG_NAME FM_P2E_SWA
J 0
(1240 -565);
DISPLAY 0.638298 (1240 -565);
PAINT WHITE (1240 -565);
WIRE 16 -1 (-3650 -625)(-3650 -725);
WIRE 16 -1 (-3250 -625)(-3650 -625);
WIRE 16 -1 (-3250 -750)(-3250 -625);
WIRE 16 -1 (-3250 -625)(-3250 -575);
WIRE 16 -1 (-3250 -575)(-2850 -575);
FORCEPROP 2 LAST SIG_NAME FM_P2E_FGA
J 0
(-3210 -565);
DISPLAY 0.638298 (-3210 -565);
PAINT WHITE (-3210 -565);
WIRE 16 -1 (-3250 -375)(-3250 -575);
WIRE 16 -1 (-2075 -2325)(-2075 -2450);
WIRE 16 -1 (-1700 -2325)(-2075 -2325);
WIRE 16 -1 (-1700 -2450)(-1700 -2325);
WIRE 16 -1 (-1700 -2325)(-1700 -2275);
WIRE 16 -1 (-1700 -2275)(-1700 -2125);
WIRE 16 -1 (-1700 -2275)(-375 -2275);
FORCEPROP 2 LAST SIG_NAME FM_P2E_EQB1
J 0
(-785 -2265);
DISPLAY 0.638298 (-785 -2265);
PAINT WHITE (-785 -2265);
WIRE 16 -1 (-1225 -2350)(-1225 -2475);
WIRE 16 -1 (-825 -2350)(-1225 -2350);
WIRE 16 -1 (-825 -2500)(-825 -2350);
WIRE 16 -1 (-825 -2350)(-825 -2325);
WIRE 16 -1 (-825 -2125)(-825 -2325);
WIRE 16 -1 (-825 -2325)(-375 -2325);
FORCEPROP 2 LAST SIG_NAME FM_P2E_EQB0
J 0
(-785 -2315);
DISPLAY 0.638298 (-785 -2315);
PAINT WHITE (-785 -2315);
WIRE 16 -1 (3100 1950)(3100 2125);
WIRE 16 -1 (3100 2125)(3100 2275);
WIRE 16 -1 (3100 2125)(3775 2125);
FORCEPROP 2 LAST SIG_NAME FM_P2E_MODE
J 0
(3340 2135);
DISPLAY 0.680851 (3340 2135);
PAINT WHITE (3340 2135);
WIRE 16 -1 (-150 1500)(1075 1500);
FORCEPROP 2 LAST SIG_NAME CLK_GEN2_GPU_FPGA_OE_OR_N
J 0
(240 1510);
DISPLAY 0.680851 (240 1510);
PAINT WHITE (240 1510);
WIRE 16 -1 (-1750 1650)(-2950 1650);
FORCEPROP 2 LAST SIG_NAME FM_P2E_SWB
J 0
(-2685 1660);
DISPLAY 0.553191 (-2685 1660);
PAINT WHITE (-2685 1660);
WIRE 16 -1 (-1750 1700)(-2950 1700);
FORCEPROP 2 LAST SIG_NAME FM_P2E_SWA
J 0
(-2685 1710);
DISPLAY 0.553191 (-2685 1710);
PAINT WHITE (-2685 1710);
WIRE 16 -1 (-1750 1500)(-2950 1500);
FORCEPROP 2 LAST SIG_NAME FM_P2E_EQA1
J 0
(-2685 1510);
DISPLAY 0.553191 (-2685 1510);
PAINT WHITE (-2685 1510);
WIRE 16 -1 (-1750 1550)(-2950 1550);
FORCEPROP 2 LAST SIG_NAME FM_P2E_EQA0
J 0
(-2685 1560);
DISPLAY 0.553191 (-2685 1560);
PAINT WHITE (-2685 1560);
WIRE 16 -1 (-1750 1850)(-2950 1850);
FORCEPROP 2 LAST SIG_NAME FM_P2E_FGB
J 0
(-2685 1860);
DISPLAY 0.553191 (-2685 1860);
PAINT WHITE (-2685 1860);
WIRE 16 -1 (-3275 2450)(-3275 2575);
WIRE 16 -1 (-2900 2575)(-3275 2575);
WIRE 16 -1 (-2900 2575)(-2900 2450);
WIRE 16 -1 (-2625 2575)(-2625 2450);
WIRE 16 -1 (-2900 2575)(-2625 2575);
WIRE 16 -1 (-2625 2575)(-2350 2575);
WIRE 16 -1 (-2350 2575)(-2350 2450);
WIRE 16 -1 (-2125 2450)(-2125 2575);
WIRE 16 -1 (-2350 2575)(-2125 2575);
WIRE 16 -1 (-2125 2575)(-1875 2575);
WIRE 16 -1 (-1750 2200)(-1875 2200);
WIRE 16 -1 (-1875 2575)(-1875 2200);
WIRE 16 -1 (-1875 2200)(-1875 2150);
WIRE 16 -1 (-1750 2150)(-1875 2150);
WIRE 16 -1 (-1875 2150)(-1875 2100);
WIRE 16 -1 (-1750 2100)(-1875 2100);
WIRE 16 -1 (-1875 2100)(-1875 2050);
WIRE 16 -1 (-1875 2050)(-1750 2050);
WIRE 16 -1 (-3275 2250)(-3275 2125);
WIRE 16 -1 (-2900 2125)(-3275 2125);
WIRE 16 -1 (-2900 2125)(-2900 2250);
WIRE 16 -1 (-2900 2125)(-2625 2125);
WIRE 16 -1 (-2625 2125)(-2625 2250);
WIRE 16 -1 (-2350 2125)(-2625 2125);
WIRE 16 -1 (-2350 2125)(-2350 2250);
WIRE 16 -1 (-2125 2125)(-2350 2125);
WIRE 16 -1 (-2125 2250)(-2125 2125);
WIRE 16 -1 (-1750 1900)(-2950 1900);
FORCEPROP 2 LAST SIG_NAME FM_P2E_FGA
J 0
(-2685 1910);
DISPLAY 0.553191 (-2685 1910);
PAINT WHITE (-2685 1910);
WIRE 16 -1 (1850 1650)(-850 1650);
FORCEPROP 2 LAST SIG_NAME PU_TEST
J 0
(-680 1660);
DISPLAY 0.553191 (-680 1660);
PAINT WHITE (-680 1660);
WIRE 16 -1 (1850 1475)(1850 1650);
WIRE 16 -1 (-350 1500)(-850 1500);
FORCEPROP 2 LAST SIG_NAME FM_P2E_EN_N
J 0
(-685 1510);
DISPLAY 0.553191 (-685 1510);
PAINT WHITE (-685 1510);
WIRE 16 -1 (-4500 -575)(-4500 -700);
WIRE 16 -1 (-4125 -575)(-4500 -575);
WIRE 16 -1 (-4125 -700)(-4125 -575);
WIRE 16 -1 (-4125 -575)(-4125 -525);
WIRE 16 -1 (-4125 -525)(-4125 -375);
WIRE 16 -1 (-4125 -525)(-2850 -525);
FORCEPROP 2 LAST SIG_NAME FM_P2E_FGB
J 0
(-3210 -515);
DISPLAY 0.638298 (-3210 -515);
PAINT WHITE (-3210 -515);
WIRE 16 -1 (-3950 -1800)(-3950 -1900);
WIRE 16 -1 (-3075 -1800)(-3950 -1800);
WIRE 16 -1 (-3075 -1900)(-3075 -1800);
WIRE 16 -1 (-3475 -2325)(-3475 -2450);
WIRE 16 -1 (-3075 -2325)(-3475 -2325);
WIRE 16 -1 (-3075 -2475)(-3075 -2325);
WIRE 16 -1 (-3075 -2325)(-3075 -2300);
WIRE 16 -1 (-3075 -2100)(-3075 -2300);
WIRE 16 -1 (-3075 -2300)(-2600 -2300);
FORCEPROP 2 LAST SIG_NAME FM_P2E_EQA0
J 0
(-3035 -2290);
DISPLAY 0.638298 (-3035 -2290);
PAINT WHITE (-3035 -2290);
WIRE 16 -1 (-4325 -2300)(-4325 -2425);
WIRE 16 -1 (-3950 -2300)(-4325 -2300);
WIRE 16 -1 (-3950 -2425)(-3950 -2300);
WIRE 16 -1 (-3950 -2300)(-3950 -2250);
WIRE 16 -1 (-3950 -2250)(-3950 -2100);
WIRE 16 -1 (-3950 -2250)(-2600 -2250);
FORCEPROP 2 LAST SIG_NAME FM_P2E_EQA1
J 0
(-3035 -2240);
DISPLAY 0.638298 (-3035 -2240);
PAINT WHITE (-3035 -2240);
WIRE 16 -1 (50 1800)(-850 1800);
FORCEPROP 2 LAST SIG_NAME FM_P2E_MODE
J 0
(-690 1810);
DISPLAY 0.553191 (-690 1810);
PAINT WHITE (-690 1810);
WIRE 16 -1 (3100 475)(3100 675);
WIRE 16 -1 (3100 675)(3100 800);
WIRE 16 -1 (3100 675)(4200 675);
FORCEPROP 2 LAST SIG_NAME CLK_GEN2_GPU_FPGA_OE_OR_N
J 0
(3340 685);
DISPLAY 0.680851 (3340 685);
PAINT WHITE (3340 685);
WIRE 16 -1 (325 -75)(325 -175);
WIRE 16 -1 (1200 -75)(325 -75);
WIRE 16 -1 (1200 -175)(1200 -75);
WIRE 16 -1 (-850 850)(-775 850);
WIRE 16 -1 (-775 850)(-775 1050);
WIRE 16 -1 (-775 1050)(-850 1050);
WIRE 16 -1 (-775 1100)(-850 1100);
WIRE 16 -1 (-775 1100)(-775 1050);
WIRE 16 -1 (-775 1150)(-850 1150);
WIRE 16 -1 (-775 1150)(-775 1100);
WIRE 16 -1 (-775 1200)(-775 1150);
WIRE 16 -1 (-775 1200)(-850 1200);
WIRE 16 -1 (-775 1250)(-850 1250);
WIRE 16 -1 (-775 1250)(-775 1200);
WIRE 16 -1 (-775 1300)(-775 1250);
WIRE 16 -1 (-775 1300)(-850 1300);
WIRE 16 -1 (-775 1350)(-850 1350);
WIRE 16 -1 (-775 1350)(-775 1300);
WIRE 16 -1 (125 2200)(-850 2200);
FORCEPROP 2 LAST SIG_NAME P2E_MB_BMC_TX_BUF_DP<0>
J 0
(-685 2210);
DISPLAY 0.553191 (-685 2210);
PAINT WHITE (-685 2210);
WIRE 16 -1 (125 2150)(-850 2150);
FORCEPROP 2 LAST SIG_NAME P2E_MB_BMC_TX_BUF_DN<0>
J 0
(-685 2160);
DISPLAY 0.553191 (-685 2160);
PAINT WHITE (-685 2160);
WIRE 16 -1 (125 2000)(-850 2000);
FORCEPROP 2 LAST SIG_NAME P2E_MB_BMC_RX_BUF_C_DP<0>
J 0
(-685 2010);
DISPLAY 0.553191 (-685 2010);
PAINT WHITE (-685 2010);
WIRE 16 -1 (125 1950)(-850 1950);
FORCEPROP 2 LAST SIG_NAME P2E_MB_BMC_RX_BUF_C_DN<0>
J 0
(-685 1960);
DISPLAY 0.553191 (-685 1960);
PAINT WHITE (-685 1960);
WIRE 16 -1 (-4125 -75)(-4125 -175);
WIRE 16 -1 (-3250 -75)(-4125 -75);
WIRE 16 -1 (-3250 -175)(-3250 -75);
DOT 1 (-3250 -575);
DOT 1 (-825 -2350);
DOT 1 (-2625 2575);
DOT 1 (-2900 2575);
DOT 1 (-1875 2150);
DOT 1 (1200 -575);
DOT 1 (1200 -625);
DOT 1 (-775 1050);
DOT 1 (3100 2125);
DOT 1 (3100 675);
DOT 1 (325 -75);
DOT 1 (-775 1250);
DOT 1 (-775 1200);
DOT 1 (-775 1300);
DOT 1 (-775 1150);
DOT 1 (-775 1100);
DOT 1 (-775 850);
DOT 1 (325 -575);
DOT 1 (325 -525);
DOT 1 (-825 -2325);
DOT 1 (-1875 2575);
DOT 1 (-2125 2575);
DOT 1 (-2350 2575);
DOT 1 (-1875 2100);
DOT 1 (-1875 2200);
DOT 1 (-2350 2125);
DOT 1 (-2625 2125);
DOT 1 (-2900 2125);
DOT 1 (-3275 2125);
DOT 1 (-4125 -75);
DOT 1 (-1700 -1825);
DOT 1 (-1700 -2325);
DOT 1 (-1700 -2275);
DOT 1 (-3250 -625);
DOT 1 (-3075 -2300);
DOT 1 (-3075 -2325);
DOT 1 (-4125 -525);
DOT 1 (-4125 -575);
DOT 1 (-3950 -1800);
DOT 1 (-3950 -2250);
DOT 1 (-3950 -2300);
FORCENOTE
20210929 MODIFY FOR GT
(-4425 2975) 0;
DISPLAY LEFT (-4425 2975);
DISPLAY 2.510638 (-4425 2975);
PAINT PINK (-4425 2975);
FORCENOTE
FROM BMC
(-4150 1225) 0;
DISPLAY LEFT (-4150 1225);
DISPLAY 1.340425 (-4150 1225);
PAINT WHITE (-4150 1225);
FORCENOTE
FROM GPU FPGA
(-4400 1050) 0;
DISPLAY LEFT (-4400 1050);
DISPLAY 1.340425 (-4400 1050);
PAINT WHITE (-4400 1050);
FORCENOTE
$CDS_IMAGE|clipboard_5.jpg|2215|625
(-1350 -550) 0;
DISPLAY LEFT (-1350 -550);
FORCENOTE
$CDS_IMAGE|clipboard_4.jpg|2583|1486
(1375 -2150) 0;
DISPLAY LEFT (1375 -2150);
FORCENOTE
$CDS_IMAGE|clipboard_1_2.jpg|1850|394
(-1525 25) 0;
DISPLAY LEFT (-1525 25);
FORCENOTE
$CDS_IMAGE|clipboard_6.jpg|2305|625
(3225 -575) 0;
DISPLAY LEFT (3225 -575);
QUIT
